FILE_TYPE = MACRO_DRAWING;
SET COLOR_WIRE YELLOW;
SET COLOR_PROP ORANGE;
SET COLOR_DOT WHITE;
SET COLOR_ARC YELLOW;
SET COLOR_BODY GREEN;
SET COLOR_NOTE PURPLE;
SET PROP_DISPLAY VALUE;
SET PAGE_NUMBER P258;
FORCEADD UNIVERSAL_GND..1
(-11250 1825);
FORCEPROP 3 LASTPIN (-11250 1875) SIG_NAME GND\g
J 0
(-11240 1885);
DISPLAY 0.659574 (-11240 1885);
PAINT MONO (-11240 1885);
DISPLAY INVISIBLE (-11240 1885);
FORCEPROP 1 LAST HDL_POWER GND
J 1
(-11225 1750);
DISPLAY 0.872340 (-11225 1750);
PAINT GREEN (-11225 1750);
DISPLAY INVISIBLE (-11225 1750);
FORCEPROP 2 LAST CDS_LIB logical_power
J 0
(-11250 1825);
PAINT MONO (-11250 1825);
DISPLAY INVISIBLE (-11250 1825);
FORCEPROP 1 LAST PATH I1
J 0
(-11175 1825);
DISPLAY 0.872340 (-11175 1825);
PAINT AQUA (-11175 1825);
DISPLAY INVISIBLE (-11175 1825);
FORCEADD ISL99390FRZTR5935..1
(-9175 2100);
FORCEPROP 1 LAST PART_NUMBER AL099390004
J 0
(-9475 2900);
DISPLAY 0.617021 (-9475 2900);
PAINT BLUE (-9475 2900);
DISPLAY INVISIBLE (-9475 2900);
FORCEPROP 2 LAST PART_TYPE SMLF
J 0
(-9475 3100);
DISPLAY 0.638298 (-9475 3100);
FORCEPROP 1 LAST MATERIAL IC
J 0
(-9475 2825);
DISPLAY 0.617021 (-9475 2825);
PAINT RED (-9475 2825);
FORCEPROP 2 LAST VALUE ISL99390FRZ-TR5935
J 0
(-9475 3050);
DISPLAY 0.617021 (-9475 3050);
PAINT SKYBLUE (-9475 3050);
FORCEPROP 1 LAST LOCATION PU72_P0_4
J 0
(-9475 2975);
DISPLAY 0.617021 (-9475 2975);
PAINT AQUA (-9475 2975);
FORCEPROP 2 LASTPIN (-8775 1650) $PN 2
J 0
(-8765 1660);
DISPLAY 0.617021 (-8765 1660);
PAINT MONO (-8765 1660);
FORCEPROP 2 LASTPIN (-8775 2450) $PN 33
J 0
(-8765 2460);
DISPLAY 0.617021 (-8765 2460);
PAINT MONO (-8765 2460);
FORCEPROP 2 LASTPIN (-9625 1850) $PN 31
J 2
(-9635 1860);
DISPLAY 0.617021 (-9635 1860);
PAINT MONO (-9635 1860);
FORCEPROP 2 LASTPIN (-9625 2250) $PN 35
J 2
(-9635 2260);
DISPLAY 0.617021 (-9635 2260);
PAINT MONO (-9635 2260);
FORCEPROP 2 LASTPIN (-8775 1800) $PN 6
J 0
(-8765 1810);
DISPLAY 0.617021 (-8765 1810);
PAINT MONO (-8765 1810);
FORCEPROP 2 LASTPIN (-8775 1750) $PN 41
J 0
(-8765 1760);
DISPLAY 0.617021 (-8765 1760);
PAINT MONO (-8765 1760);
FORCEPROP 2 LASTPIN (-9625 2100) $PN 38
J 2
(-9635 2110);
DISPLAY 0.617021 (-9635 2110);
PAINT MONO (-9635 2110);
FORCEPROP 2 LASTPIN (-9625 1800) $PN 37
J 2
(-9635 1810);
DISPLAY 0.617021 (-9635 1810);
PAINT MONO (-9635 1810);
FORCEPROP 2 LASTPIN (-8775 1600) $PN 5
J 0
(-8765 1610);
DISPLAY 0.617021 (-8765 1610);
PAINT MONO (-8765 1610);
FORCEPROP 2 LASTPIN (-8775 1550) $PN 7_9-20_24
J 0
(-8765 1560);
DISPLAY 0.617021 (-8765 1560);
PAINT MONO (-8765 1560);
FORCEPROP 2 LASTPIN (-8775 1500) $PN 40
J 0
(-8765 1510);
DISPLAY 0.617021 (-8765 1510);
PAINT MONO (-8765 1510);
FORCEPROP 2 LASTPIN (-8775 2200) $PN 32
J 0
(-8765 2210);
DISPLAY 0.617021 (-8765 2210);
PAINT MONO (-8765 2210);
FORCEPROP 2 LASTPIN (-9625 2750) $PN 4
J 2
(-9635 2760);
DISPLAY 0.617021 (-9635 2760);
PAINT MONO (-9635 2760);
FORCEPROP 2 LASTPIN (-9625 1500) $PN 34
J 2
(-9635 1510);
DISPLAY 0.617021 (-9635 1510);
PAINT MONO (-9635 1510);
FORCEPROP 2 LASTPIN (-9625 2000) $PN 39
J 2
(-9635 2010);
DISPLAY 0.617021 (-9635 2010);
PAINT MONO (-9635 2010);
FORCEPROP 2 LASTPIN (-8775 2100) $PN 10_19
J 0
(-8765 2110);
DISPLAY 0.617021 (-8765 2110);
PAINT MONO (-8765 2110);
FORCEPROP 2 LASTPIN (-9625 1600) $PN 36
J 2
(-9635 1610);
DISPLAY 0.617021 (-9635 1610);
PAINT MONO (-9635 1610);
FORCEPROP 2 LASTPIN (-9625 2450) $PN 3
J 2
(-9635 2460);
DISPLAY 0.617021 (-9635 2460);
PAINT MONO (-9635 2460);
FORCEPROP 2 LASTPIN (-8775 2750) $PN 25_29
J 0
(-8765 2760);
DISPLAY 0.617021 (-8765 2760);
PAINT MONO (-8765 2760);
FORCEPROP 2 LASTPIN (-8775 2700) $PN 30
J 0
(-8765 2710);
DISPLAY 0.617021 (-8765 2710);
PAINT MONO (-8765 2710);
FORCEPROP 2 LASTPIN (-8775 1850) $PN 1
J 0
(-8765 1860);
DISPLAY 0.617021 (-8765 1860);
PAINT MONO (-8765 1860);
FORCEPROP 2 LAST CDS_LIB pure_quanta
J 0
(-9175 2100);
DISPLAY INVISIBLE (-9175 2100);
FORCEPROP 1 LAST CDS_LMAN_SYM_OUTLINE -300,700,250,-650
J 0
(-9175 2100);
DISPLAY 0.468085 (-9175 2100);
PAINT GREEN (-9175 2100);
DISPLAY INVISIBLE (-9175 2100);
FORCEPROP 1 LAST NEEDS_NO_SIZE TRUE
J 0
(-9175 2100);
DISPLAY 0.723404 (-9175 2100);
PAINT GREEN (-9175 2100);
DISPLAY INVISIBLE (-9175 2100);
FORCEPROP 1 LAST PATH I10
J 0
(-9175 2100);
DISPLAY 0.723404 (-9175 2100);
PAINT GREEN (-9175 2100);
DISPLAY INVISIBLE (-9175 2100);
FORCEPROP 2 LAST $SEC 1
J 0
(-9475 3025);
DISPLAY 0.680851 (-9475 3025);
PAINT MONO (-9475 3025);
DISPLAY INVISIBLE (-9475 3025);
FORCEPROP 2 LAST CDS_SEC 1
J 0
(-9425 3100);
DISPLAY 1.021277 (-9425 3100);
DISPLAY INVISIBLE (-9425 3100);
FORCEADD Q_RES..2
(-10700 2950);
FORCEPROP 1 LAST PART_NUMBER CS-2202FB01
J 0
(-10660 2825);
DISPLAY 0.617021 (-10660 2825);
PAINT BLUE (-10660 2825);
DISPLAY INVISIBLE (-10660 2825);
FORCEPROP 1 LAST TOLERANCE 1%
J 0
(-10655 2975);
DISPLAY 0.617021 (-10655 2975);
PAINT SKYBLUE (-10655 2975);
FORCEPROP 1 LAST WATTAGE 1/16W
J 0
(-10660 2925);
DISPLAY 0.617021 (-10660 2925);
PAINT SKYBLUE (-10660 2925);
FORCEPROP 1 LAST PACK_TYPE 0402LF
J 0
(-10660 2775);
DISPLAY 0.617021 (-10660 2775);
PAINT SKYBLUE (-10660 2775);
FORCEPROP 1 LAST MATERIAL CHIP
J 0
(-10660 2875);
DISPLAY 0.617021 (-10660 2875);
PAINT RED (-10660 2875);
FORCEPROP 1 LAST VALUE 2.2
J 0
(-10655 3025);
DISPLAY 0.617021 (-10655 3025);
PAINT SKYBLUE (-10655 3025);
FORCEPROP 1 LAST LOCATION PR1300
J 0
(-10655 3075);
DISPLAY 0.617021 (-10655 3075);
PAINT AQUA (-10655 3075);
FORCEPROP 1 LASTPIN (-10700 3050) $PN 1
J 0
(-10695 3012);
DISPLAY 0.617021 (-10695 3012);
PAINT MONO (-10695 3012);
FORCEPROP 1 LASTPIN (-10700 2850) $PN 2
J 0
(-10695 2860);
DISPLAY 0.617021 (-10695 2860);
PAINT MONO (-10695 2860);
FORCEPROP 2 LAST CDS_LIB pure_quanta
J 0
(-10700 2950);
DISPLAY INVISIBLE (-10700 2950);
FORCEPROP 1 LAST PATH I11
J 0
(-10650 3125);
DISPLAY 0.978723 (-10650 3125);
PAINT WHITE (-10650 3125);
DISPLAY INVISIBLE (-10650 3125);
FORCEPROP 1 LAST LOCATION PR1300
J 0
(-10650 3125);
DISPLAY 1.021277 (-10650 3125);
PAINT AQUA (-10650 3125);
DISPLAY INVISIBLE (-10650 3125);
FORCEPROP 0 LAST $SEC 1
J 0
(-10650 3125);
DISPLAY 0.680851 (-10650 3125);
PAINT MONO (-10650 3125);
DISPLAY INVISIBLE (-10650 3125);
FORCEPROP 0 LAST CDS_SEC 1
J 0
(-10650 3125);
DISPLAY 1.021277 (-10650 3125);
DISPLAY INVISIBLE (-10650 3125);
FORCEADD VCC15..1
(-10700 3300);
FORCEPROP 3 LASTPIN (-10700 3250) SIG_NAME PVCCFA_EHV_FIVRA_CPU0_PVCC2\g
J 0
(-10690 3260);
DISPLAY 0.659574 (-10690 3260);
PAINT MONO (-10690 3260);
DISPLAY INVISIBLE (-10690 3260);
FORCEPROP 1 LAST HDL_POWER PVCCFA_EHV_FIVRA_CPU0_PVCC2
J 1
(-10700 3350);
DISPLAY 0.617021 (-10700 3350);
PAINT GREEN (-10700 3350);
FORCEPROP 2 LAST CDS_LIB logical_power
J 0
(-10700 3300);
DISPLAY INVISIBLE (-10700 3300);
FORCEPROP 1 LAST PATH I12
J 0
(-10650 3325);
DISPLAY 0.872340 (-10650 3325);
PAINT AQUA (-10650 3325);
DISPLAY INVISIBLE (-10650 3325);
FORCEADD Q_CAP..1
(-10700 2550);
FORCEPROP 1 LAST PART_NUMBER CH5222KEB01
J 0
(-10650 2375);
DISPLAY 0.617021 (-10650 2375);
PAINT BLUE (-10650 2375);
DISPLAY INVISIBLE (-10650 2375);
FORCEPROP 1 LAST PACK_TYPE C0402
J 0
(-10650 2425);
DISPLAY 0.617021 (-10650 2425);
PAINT SKYBLUE (-10650 2425);
FORCEPROP 1 LAST MATERIAL X6S
J 0
(-10650 2475);
DISPLAY 0.617021 (-10650 2475);
PAINT RED (-10650 2475);
FORCEPROP 1 LAST TOLERANCE 10%
J 0
(-10650 2525);
DISPLAY 0.617021 (-10650 2525);
PAINT SKYBLUE (-10650 2525);
FORCEPROP 1 LAST VOLTAGE 10V
J 0
(-10650 2575);
DISPLAY 0.617021 (-10650 2575);
PAINT SKYBLUE (-10650 2575);
FORCEPROP 1 LAST VALUE 2.2UF
J 0
(-10650 2625);
DISPLAY 0.617021 (-10650 2625);
PAINT SKYBLUE (-10650 2625);
FORCEPROP 1 LAST LOCATION PC1172
J 0
(-10650 2675);
DISPLAY 0.617021 (-10650 2675);
PAINT AQUA (-10650 2675);
FORCEPROP 1 LASTPIN (-10700 2650) $PN 1
J 0
(-10690 2630);
DISPLAY 0.617021 (-10690 2630);
PAINT MONO (-10690 2630);
FORCEPROP 1 LASTPIN (-10700 2450) $PN 2
J 0
(-10690 2430);
DISPLAY 0.617021 (-10690 2430);
PAINT MONO (-10690 2430);
FORCEPROP 2 LAST CDS_LIB pure_quanta
J 0
(-10700 2550);
DISPLAY INVISIBLE (-10700 2550);
FORCEPROP 1 LAST PATH I13
J 0
(-10650 2700);
DISPLAY 0.978723 (-10650 2700);
PAINT WHITE (-10650 2700);
DISPLAY INVISIBLE (-10650 2700);
FORCEPROP 1 LAST LOCATION PC1172
J 0
(-10650 2725);
DISPLAY 1.021277 (-10650 2725);
PAINT AQUA (-10650 2725);
DISPLAY INVISIBLE (-10650 2725);
FORCEPROP 0 LAST $SEC 1
J 0
(-10650 2725);
DISPLAY 0.680851 (-10650 2725);
PAINT MONO (-10650 2725);
DISPLAY INVISIBLE (-10650 2725);
FORCEPROP 0 LAST CDS_SEC 1
J 0
(-10650 2725);
DISPLAY 1.021277 (-10650 2725);
DISPLAY INVISIBLE (-10650 2725);
FORCEADD UNIVERSAL_GND..1
(-11175 4225);
FORCEPROP 3 LASTPIN (-11175 4275) SIG_NAME GND\g
J 0
(-11165 4285);
DISPLAY 0.659574 (-11165 4285);
PAINT MONO (-11165 4285);
DISPLAY INVISIBLE (-11165 4285);
FORCEPROP 1 LAST HDL_POWER GND
J 1
(-11150 4150);
DISPLAY 0.872340 (-11150 4150);
PAINT GREEN (-11150 4150);
DISPLAY INVISIBLE (-11150 4150);
FORCEPROP 2 LAST CDS_LIB logical_power
J 0
(-11175 4225);
PAINT MONO (-11175 4225);
DISPLAY INVISIBLE (-11175 4225);
FORCEPROP 1 LAST PATH I14
J 0
(-11100 4225);
DISPLAY 0.872340 (-11100 4225);
PAINT AQUA (-11100 4225);
DISPLAY INVISIBLE (-11100 4225);
FORCEADD Q_RES..2
R 2
(-11175 4450);
FORCEPROP 1 LAST PART_NUMBER CS28872FB01
J 2
(-11225 4325);
DISPLAY 0.617021 (-11225 4325);
PAINT BLUE (-11225 4325);
DISPLAY INVISIBLE (-11225 4325);
FORCEPROP 1 LAST TOLERANCE 1%
J 2
(-11230 4475);
DISPLAY 0.617021 (-11230 4475);
PAINT SKYBLUE (-11230 4475);
FORCEPROP 1 LAST MATERIAL EMPTY
J 2
(-11225 4375);
DISPLAY 0.617021 (-11225 4375);
PAINT RED (-11225 4375);
FORCEPROP 1 LAST WATTAGE 1/16W
J 2
(-11225 4425);
DISPLAY 0.617021 (-11225 4425);
PAINT SKYBLUE (-11225 4425);
FORCEPROP 1 LAST VALUE 8.87K
J 2
(-11230 4525);
DISPLAY 0.617021 (-11230 4525);
PAINT SKYBLUE (-11230 4525);
FORCEPROP 1 LAST PACK_TYPE 0402LF
J 2
(-11225 4275);
DISPLAY 0.617021 (-11225 4275);
PAINT SKYBLUE (-11225 4275);
FORCEPROP 1 LAST LOCATION PR1298
J 2
(-11220 4575);
DISPLAY 0.617021 (-11220 4575);
PAINT AQUA (-11220 4575);
FORCEPROP 1 LASTPIN (-11175 4550) $PN 1
J 2
(-11180 4512);
DISPLAY 0.617021 (-11180 4512);
PAINT MONO (-11180 4512);
FORCEPROP 1 LASTPIN (-11175 4350) $PN 2
J 2
(-11180 4360);
DISPLAY 0.617021 (-11180 4360);
PAINT MONO (-11180 4360);
FORCEPROP 2 LAST CDS_LIB pure_quanta
J 2
(-11175 4450);
DISPLAY INVISIBLE (-11175 4450);
FORCEPROP 1 LAST PATH I15
J 2
(-11225 4625);
DISPLAY 0.978723 (-11225 4625);
PAINT WHITE (-11225 4625);
DISPLAY INVISIBLE (-11225 4625);
FORCEPROP 1 LAST LOCATION PR1298
J 2
(-11225 4625);
DISPLAY 1.021277 (-11225 4625);
PAINT AQUA (-11225 4625);
DISPLAY INVISIBLE (-11225 4625);
FORCEPROP 0 LAST $SEC 1
J 2
(-11225 4625);
DISPLAY 0.680851 (-11225 4625);
PAINT MONO (-11225 4625);
DISPLAY INVISIBLE (-11225 4625);
FORCEPROP 0 LAST CDS_SEC 1
J 2
(-11225 4625);
DISPLAY 1.021277 (-11225 4625);
DISPLAY INVISIBLE (-11225 4625);
FORCEADD OFFPAGE..1
(-10700 4300);
FORCEPROP 2 LAST $XR0 266 
J 0
(-10952 4300);
DISPLAY 0.638298 (-10952 4300);
PAINT MONO (-10952 4300);
FORCEPROP 1 LAST COMMENT_BODY TRUE
J 0
(-10575 4200);
DISPLAY 0.872340 (-10575 4200);
PAINT GREEN (-10575 4200);
DISPLAY INVISIBLE (-10575 4200);
FORCEPROP 1 LAST OFFPAGE TRUE
J 0
(-10375 4175);
DISPLAY 0.872340 (-10375 4175);
PAINT GREEN (-10375 4175);
DISPLAY INVISIBLE (-10375 4175);
FORCEPROP 2 LAST CDS_LIB standard
J 0
(-10700 4300);
DISPLAY INVISIBLE (-10700 4300);
FORCEPROP 2 LAST PATH I16
J 0
(-10950 4350);
DISPLAY 1.021277 (-10950 4350);
DISPLAY INVISIBLE (-10950 4350);
FORCEADD OFFPAGE..5
(-10700 4400);
FORCEPROP 2 LAST $XR2 266 
J 0
(-10955 4436);
DISPLAY 0.638298 (-10955 4436);
PAINT MONO (-10955 4436);
FORCEPROP 2 LAST $XR1 272 
J 0
(-10955 4364);
DISPLAY 0.638298 (-10955 4364);
PAINT MONO (-10955 4364);
FORCEPROP 2 LAST $XR0 271 
J 0
(-10955 4400);
DISPLAY 0.638298 (-10955 4400);
PAINT MONO (-10955 4400);
FORCEPROP 1 LAST COMMENT_BODY TRUE
J 0
(-10600 4325);
DISPLAY 0.872340 (-10600 4325);
PAINT GREEN (-10600 4325);
DISPLAY INVISIBLE (-10600 4325);
FORCEPROP 1 LAST OFFPAGE TRUE
J 0
(-10375 4275);
DISPLAY 0.872340 (-10375 4275);
PAINT GREEN (-10375 4275);
DISPLAY INVISIBLE (-10375 4275);
FORCEPROP 2 LAST CDS_LIB standard
J 0
(-10700 4400);
DISPLAY INVISIBLE (-10700 4400);
FORCEPROP 2 LAST PATH I17
J 0
(-10950 4475);
DISPLAY 1.021277 (-10950 4475);
DISPLAY INVISIBLE (-10950 4475);
FORCEADD Q_CAP..1
(-10175 2950);
FORCEPROP 1 LAST PART_NUMBER CH5222KEB01
J 0
(-10125 2800);
DISPLAY 0.617021 (-10125 2800);
PAINT BLUE (-10125 2800);
DISPLAY INVISIBLE (-10125 2800);
FORCEPROP 1 LAST VALUE 2.2UF
J 0
(-10125 3000);
DISPLAY 0.617021 (-10125 3000);
PAINT SKYBLUE (-10125 3000);
FORCEPROP 1 LAST TOLERANCE 10%
J 0
(-10125 2900);
DISPLAY 0.617021 (-10125 2900);
PAINT SKYBLUE (-10125 2900);
FORCEPROP 1 LAST PACK_TYPE C0402
J 0
(-10125 2750);
DISPLAY 0.617021 (-10125 2750);
PAINT SKYBLUE (-10125 2750);
FORCEPROP 1 LAST MATERIAL X6S
J 0
(-10125 2850);
DISPLAY 0.617021 (-10125 2850);
PAINT RED (-10125 2850);
FORCEPROP 1 LAST VOLTAGE 10V
J 0
(-10125 2950);
DISPLAY 0.617021 (-10125 2950);
PAINT SKYBLUE (-10125 2950);
FORCEPROP 1 LAST LOCATION PC1214_P0_4
J 0
(-10125 3050);
DISPLAY 0.617021 (-10125 3050);
PAINT AQUA (-10125 3050);
FORCEPROP 1 LASTPIN (-10175 3050) $PN 1
J 0
(-10165 3030);
DISPLAY 0.617021 (-10165 3030);
FORCEPROP 1 LASTPIN (-10175 2850) $PN 2
J 0
(-10165 2830);
DISPLAY 0.617021 (-10165 2830);
FORCEPROP 2 LAST CDS_LIB pure_quanta
J 0
(-10175 2950);
PAINT MONO (-10175 2950);
DISPLAY INVISIBLE (-10175 2950);
FORCEPROP 1 LAST PATH I18
J 0
(-10125 3100);
DISPLAY 0.978723 (-10125 3100);
PAINT WHITE (-10125 3100);
DISPLAY INVISIBLE (-10125 3100);
FORCEPROP 2 LAST $SEC 1
J 0
(-10125 3150);
DISPLAY 0.680851 (-10125 3150);
PAINT MONO (-10125 3150);
DISPLAY INVISIBLE (-10125 3150);
FORCEPROP 2 LAST CDS_SEC 1
J 0
(-10125 3150);
DISPLAY 1.021277 (-10125 3150);
DISPLAY INVISIBLE (-10125 3150);
FORCEADD UNIVERSAL_GND..1
(-10175 2700);
FORCEPROP 3 LASTPIN (-10175 2750) SIG_NAME GND\g
J 0
(-10165 2760);
DISPLAY 0.659574 (-10165 2760);
PAINT MONO (-10165 2760);
DISPLAY INVISIBLE (-10165 2760);
FORCEPROP 1 LAST HDL_POWER GND
J 1
(-10150 2625);
DISPLAY 0.872340 (-10150 2625);
PAINT GREEN (-10150 2625);
DISPLAY INVISIBLE (-10150 2625);
FORCEPROP 2 LAST CDS_LIB logical_power
J 0
(-10175 2700);
PAINT MONO (-10175 2700);
DISPLAY INVISIBLE (-10175 2700);
FORCEPROP 1 LAST PATH I19
J 0
(-10100 2700);
DISPLAY 0.872340 (-10100 2700);
PAINT AQUA (-10100 2700);
DISPLAY INVISIBLE (-10100 2700);
FORCEADD UNIVERSAL_GND..1
(-11200 1375);
FORCEPROP 3 LASTPIN (-11200 1425) SIG_NAME GND\g
J 0
(-11190 1435);
DISPLAY 0.659574 (-11190 1435);
PAINT MONO (-11190 1435);
DISPLAY INVISIBLE (-11190 1435);
FORCEPROP 1 LAST HDL_POWER GND
J 1
(-11175 1300);
DISPLAY 0.872340 (-11175 1300);
PAINT GREEN (-11175 1300);
DISPLAY INVISIBLE (-11175 1300);
FORCEPROP 2 LAST CDS_LIB logical_power
J 0
(-11200 1375);
PAINT MONO (-11200 1375);
DISPLAY INVISIBLE (-11200 1375);
FORCEPROP 1 LAST PATH I2
J 0
(-11125 1375);
DISPLAY 0.872340 (-11125 1375);
PAINT AQUA (-11125 1375);
DISPLAY INVISIBLE (-11125 1375);
FORCEADD UNIVERSAL_GND..1
(-11250 4625);
FORCEPROP 3 LASTPIN (-11250 4675) SIG_NAME GND\g
J 0
(-11240 4685);
DISPLAY 0.659574 (-11240 4685);
PAINT MONO (-11240 4685);
DISPLAY INVISIBLE (-11240 4685);
FORCEPROP 1 LAST HDL_POWER GND
J 1
(-11225 4550);
DISPLAY 0.872340 (-11225 4550);
PAINT GREEN (-11225 4550);
DISPLAY INVISIBLE (-11225 4550);
FORCEPROP 2 LAST CDS_LIB logical_power
J 0
(-11250 4625);
PAINT MONO (-11250 4625);
DISPLAY INVISIBLE (-11250 4625);
FORCEPROP 1 LAST PATH I20
J 0
(-11175 4625);
DISPLAY 0.872340 (-11175 4625);
PAINT AQUA (-11175 4625);
DISPLAY INVISIBLE (-11175 4625);
FORCEADD OFFPAGE..1
(-10700 4800);
FORCEPROP 2 LAST $XR6 272 
J 0
(-11672 4800);
DISPLAY 0.638298 (-11672 4800);
PAINT MONO (-11672 4800);
FORCEPROP 2 LAST $XR5 271 
J 0
(-11552 4800);
DISPLAY 0.638298 (-11552 4800);
PAINT MONO (-11552 4800);
FORCEPROP 2 LAST $XR4 270 
J 0
(-11432 4800);
DISPLAY 0.638298 (-11432 4800);
PAINT MONO (-11432 4800);
FORCEPROP 2 LAST $XR3 269 
J 0
(-11312 4800);
DISPLAY 0.638298 (-11312 4800);
PAINT MONO (-11312 4800);
FORCEPROP 2 LAST $XR2 268 
J 0
(-11192 4800);
DISPLAY 0.638298 (-11192 4800);
PAINT MONO (-11192 4800);
FORCEPROP 2 LAST $XR1 267 
J 0
(-11072 4800);
DISPLAY 0.638298 (-11072 4800);
PAINT MONO (-11072 4800);
FORCEPROP 2 LAST $XR0 266 
J 0
(-10952 4800);
DISPLAY 0.638298 (-10952 4800);
PAINT MONO (-10952 4800);
FORCEPROP 1 LAST COMMENT_BODY TRUE
J 0
(-10575 4700);
DISPLAY 0.872340 (-10575 4700);
PAINT GREEN (-10575 4700);
DISPLAY INVISIBLE (-10575 4700);
FORCEPROP 1 LAST OFFPAGE TRUE
J 0
(-10375 4675);
DISPLAY 0.872340 (-10375 4675);
PAINT GREEN (-10375 4675);
DISPLAY INVISIBLE (-10375 4675);
FORCEPROP 2 LAST CDS_LIB standard
J 0
(-10700 4800);
DISPLAY INVISIBLE (-10700 4800);
FORCEPROP 2 LAST PATH I21
J 0
(-10950 4850);
DISPLAY 1.021277 (-10950 4850);
DISPLAY INVISIBLE (-10950 4850);
FORCEADD OFFPAGE..5
(-10700 4900);
FORCEPROP 2 LAST $XR0 266 
J 0
(-10955 4900);
DISPLAY 0.638298 (-10955 4900);
PAINT MONO (-10955 4900);
FORCEPROP 1 LAST COMMENT_BODY TRUE
J 0
(-10600 4825);
DISPLAY 0.872340 (-10600 4825);
PAINT GREEN (-10600 4825);
DISPLAY INVISIBLE (-10600 4825);
FORCEPROP 1 LAST OFFPAGE TRUE
J 0
(-10375 4775);
DISPLAY 0.872340 (-10375 4775);
PAINT GREEN (-10375 4775);
DISPLAY INVISIBLE (-10375 4775);
FORCEPROP 2 LAST CDS_LIB standard
J 0
(-10700 4900);
DISPLAY INVISIBLE (-10700 4900);
FORCEPROP 2 LAST PATH I22
J 0
(-10950 4950);
DISPLAY 1.021277 (-10950 4950);
DISPLAY INVISIBLE (-10950 4950);
FORCEADD Q_CAP..1
(-10700 5350);
FORCEPROP 1 LAST PART_NUMBER CH5222KEB01
J 0
(-10650 5175);
DISPLAY 0.617021 (-10650 5175);
PAINT BLUE (-10650 5175);
DISPLAY INVISIBLE (-10650 5175);
FORCEPROP 1 LAST PACK_TYPE C0402
J 0
(-10650 5225);
DISPLAY 0.617021 (-10650 5225);
PAINT SKYBLUE (-10650 5225);
FORCEPROP 1 LAST VOLTAGE 10V
J 0
(-10650 5375);
DISPLAY 0.617021 (-10650 5375);
PAINT SKYBLUE (-10650 5375);
FORCEPROP 1 LAST VALUE 2.2UF
J 0
(-10650 5425);
DISPLAY 0.617021 (-10650 5425);
PAINT SKYBLUE (-10650 5425);
FORCEPROP 1 LAST MATERIAL X6S
J 0
(-10650 5275);
DISPLAY 0.617021 (-10650 5275);
PAINT RED (-10650 5275);
FORCEPROP 1 LAST TOLERANCE 10%
J 0
(-10650 5325);
DISPLAY 0.617021 (-10650 5325);
PAINT SKYBLUE (-10650 5325);
FORCEPROP 1 LAST LOCATION PC1171
J 0
(-10650 5475);
DISPLAY 0.617021 (-10650 5475);
PAINT AQUA (-10650 5475);
FORCEPROP 1 LASTPIN (-10700 5450) $PN 1
J 0
(-10690 5430);
DISPLAY 0.617021 (-10690 5430);
PAINT MONO (-10690 5430);
FORCEPROP 1 LASTPIN (-10700 5250) $PN 2
J 0
(-10690 5230);
DISPLAY 0.617021 (-10690 5230);
PAINT MONO (-10690 5230);
FORCEPROP 2 LAST CDS_LIB pure_quanta
J 0
(-10700 5350);
DISPLAY INVISIBLE (-10700 5350);
FORCEPROP 1 LAST PATH I23
J 0
(-10650 5500);
DISPLAY 0.978723 (-10650 5500);
PAINT WHITE (-10650 5500);
DISPLAY INVISIBLE (-10650 5500);
FORCEPROP 1 LAST LOCATION PC1171
J 0
(-10650 5525);
DISPLAY 1.021277 (-10650 5525);
PAINT AQUA (-10650 5525);
DISPLAY INVISIBLE (-10650 5525);
FORCEPROP 0 LAST $SEC 1
J 0
(-10650 5525);
DISPLAY 0.680851 (-10650 5525);
PAINT MONO (-10650 5525);
DISPLAY INVISIBLE (-10650 5525);
FORCEPROP 0 LAST CDS_SEC 1
J 0
(-10650 5525);
DISPLAY 1.021277 (-10650 5525);
DISPLAY INVISIBLE (-10650 5525);
FORCEADD UNIVERSAL_GND..1
(-10700 5100);
FORCEPROP 3 LASTPIN (-10700 5150) SIG_NAME GND\g
J 0
(-10690 5160);
DISPLAY 0.659574 (-10690 5160);
PAINT MONO (-10690 5160);
DISPLAY INVISIBLE (-10690 5160);
FORCEPROP 1 LAST HDL_POWER GND
J 1
(-10675 5025);
DISPLAY 0.872340 (-10675 5025);
PAINT GREEN (-10675 5025);
DISPLAY INVISIBLE (-10675 5025);
FORCEPROP 2 LAST CDS_LIB logical_power
J 0
(-10700 5100);
PAINT MONO (-10700 5100);
DISPLAY INVISIBLE (-10700 5100);
FORCEPROP 1 LAST PATH I24
J 0
(-10625 5100);
DISPLAY 0.872340 (-10625 5100);
PAINT AQUA (-10625 5100);
DISPLAY INVISIBLE (-10625 5100);
FORCEADD Q_CAP..2
(-10425 4700);
FORCEPROP 1 LAST PART_NUMBER CH4104K1B00
J 1
(-10150 4750);
DISPLAY 0.617021 (-10150 4750);
PAINT BLUE (-10150 4750);
DISPLAY INVISIBLE (-10150 4750);
FORCEPROP 1 LAST MATERIAL X7R
J 0
(-9950 4750);
DISPLAY 0.617021 (-9950 4750);
PAINT RED (-9950 4750);
FORCEPROP 1 LAST VALUE 0.1UF
J 2
(-10150 4700);
DISPLAY 0.617021 (-10150 4700);
PAINT SKYBLUE (-10150 4700);
FORCEPROP 1 LAST VOLTAGE 25V
J 0
(-10125 4700);
DISPLAY 0.617021 (-10125 4700);
PAINT SKYBLUE (-10125 4700);
FORCEPROP 1 LAST PACK_TYPE 0402
J 1
(-9950 4700);
DISPLAY 0.617021 (-9950 4700);
PAINT SKYBLUE (-9950 4700);
FORCEPROP 1 LAST TOLERANCE 10%
J 2
(-9775 4725);
DISPLAY 0.617021 (-9775 4725);
PAINT SKYBLUE (-9775 4725);
FORCEPROP 1 LAST LOCATION PC1351
J 1
(-10625 4700);
DISPLAY 0.617021 (-10625 4700);
PAINT AQUA (-10625 4700);
FORCEPROP 1 LASTPIN (-10525 4700) $PN 1
J 0
(-10535 4715);
DISPLAY 0.617021 (-10535 4715);
FORCEPROP 1 LASTPIN (-10325 4700) $PN 2
J 0
(-10340 4715);
DISPLAY 0.617021 (-10340 4715);
FORCEPROP 2 LAST CDS_LIB pure_quanta
J 0
(-10425 4700);
PAINT MONO (-10425 4700);
DISPLAY INVISIBLE (-10425 4700);
FORCEPROP 1 LAST PATH I25
J 0
(-10425 4900);
DISPLAY 0.978723 (-10425 4900);
PAINT WHITE (-10425 4900);
DISPLAY INVISIBLE (-10425 4900);
FORCEPROP 2 LAST $SEC 1
J 0
(-10425 4950);
DISPLAY 0.680851 (-10425 4950);
PAINT MONO (-10425 4950);
DISPLAY INVISIBLE (-10425 4950);
FORCEPROP 2 LAST CDS_SEC 1
J 0
(-10425 4950);
DISPLAY 1.021277 (-10425 4950);
DISPLAY INVISIBLE (-10425 4950);
FORCEADD Q_RES..2
(-10700 5750);
FORCEPROP 1 LAST PART_NUMBER CS-2202FB01
J 0
(-10660 5625);
DISPLAY 0.617021 (-10660 5625);
PAINT BLUE (-10660 5625);
DISPLAY INVISIBLE (-10660 5625);
FORCEPROP 1 LAST PACK_TYPE 0402LF
J 0
(-10660 5575);
DISPLAY 0.617021 (-10660 5575);
PAINT SKYBLUE (-10660 5575);
FORCEPROP 1 LAST TOLERANCE 1%
J 0
(-10655 5775);
DISPLAY 0.617021 (-10655 5775);
PAINT SKYBLUE (-10655 5775);
FORCEPROP 1 LAST VALUE 2.2
J 0
(-10655 5825);
DISPLAY 0.617021 (-10655 5825);
PAINT SKYBLUE (-10655 5825);
FORCEPROP 1 LAST MATERIAL CHIP
J 0
(-10660 5675);
DISPLAY 0.617021 (-10660 5675);
PAINT RED (-10660 5675);
FORCEPROP 1 LAST WATTAGE 1/16W
J 0
(-10660 5725);
DISPLAY 0.617021 (-10660 5725);
PAINT SKYBLUE (-10660 5725);
FORCEPROP 1 LAST LOCATION PR1299
J 0
(-10655 5875);
DISPLAY 0.617021 (-10655 5875);
PAINT AQUA (-10655 5875);
FORCEPROP 1 LASTPIN (-10700 5850) $PN 1
J 0
(-10695 5812);
DISPLAY 0.617021 (-10695 5812);
PAINT MONO (-10695 5812);
FORCEPROP 1 LASTPIN (-10700 5650) $PN 2
J 0
(-10695 5660);
DISPLAY 0.617021 (-10695 5660);
PAINT MONO (-10695 5660);
FORCEPROP 2 LAST CDS_LIB pure_quanta
J 0
(-10700 5750);
DISPLAY INVISIBLE (-10700 5750);
FORCEPROP 1 LAST PATH I26
J 0
(-10650 5925);
DISPLAY 0.978723 (-10650 5925);
PAINT WHITE (-10650 5925);
DISPLAY INVISIBLE (-10650 5925);
FORCEPROP 0 LAST $SEC 1
J 0
(-10650 5925);
DISPLAY 0.680851 (-10650 5925);
PAINT MONO (-10650 5925);
DISPLAY INVISIBLE (-10650 5925);
FORCEPROP 0 LAST CDS_SEC 1
J 0
(-10650 5925);
DISPLAY 1.021277 (-10650 5925);
DISPLAY INVISIBLE (-10650 5925);
FORCEADD VCC15..1
(-10700 6075);
FORCEPROP 3 LASTPIN (-10700 6025) SIG_NAME PVCCFA_EHV_FIVRA_CPU0_PVCC1\g
J 0
(-10690 6035);
DISPLAY 0.659574 (-10690 6035);
PAINT MONO (-10690 6035);
DISPLAY INVISIBLE (-10690 6035);
FORCEPROP 1 LAST HDL_POWER PVCCFA_EHV_FIVRA_CPU0_PVCC1
J 1
(-10700 6125);
DISPLAY 0.617021 (-10700 6125);
PAINT GREEN (-10700 6125);
FORCEPROP 2 LAST CDS_LIB logical_power
J 0
(-10700 6075);
DISPLAY INVISIBLE (-10700 6075);
FORCEPROP 1 LAST PATH I27
J 0
(-10650 6100);
DISPLAY 0.872340 (-10650 6100);
PAINT AQUA (-10650 6100);
DISPLAY INVISIBLE (-10650 6100);
FORCEADD Q_CAP..1
(-10175 5750);
FORCEPROP 1 LAST PART_NUMBER CH5222KEB01
J 0
(-10125 5600);
DISPLAY 0.617021 (-10125 5600);
PAINT BLUE (-10125 5600);
DISPLAY INVISIBLE (-10125 5600);
FORCEPROP 1 LAST VALUE 2.2UF
J 0
(-10125 5800);
DISPLAY 0.617021 (-10125 5800);
PAINT SKYBLUE (-10125 5800);
FORCEPROP 1 LAST PACK_TYPE C0402
J 0
(-10125 5550);
DISPLAY 0.617021 (-10125 5550);
PAINT SKYBLUE (-10125 5550);
FORCEPROP 1 LAST VOLTAGE 10V
J 0
(-10125 5750);
DISPLAY 0.617021 (-10125 5750);
PAINT SKYBLUE (-10125 5750);
FORCEPROP 1 LAST MATERIAL X6S
J 0
(-10125 5650);
DISPLAY 0.617021 (-10125 5650);
PAINT RED (-10125 5650);
FORCEPROP 1 LAST TOLERANCE 10%
J 0
(-10125 5700);
DISPLAY 0.617021 (-10125 5700);
PAINT SKYBLUE (-10125 5700);
FORCEPROP 1 LAST LOCATION PC1213_P0_3
J 0
(-10125 5850);
DISPLAY 0.617021 (-10125 5850);
PAINT AQUA (-10125 5850);
FORCEPROP 1 LASTPIN (-10175 5850) $PN 1
J 0
(-10165 5830);
DISPLAY 0.617021 (-10165 5830);
FORCEPROP 1 LASTPIN (-10175 5650) $PN 2
J 0
(-10165 5630);
DISPLAY 0.617021 (-10165 5630);
FORCEPROP 2 LAST CDS_LIB pure_quanta
J 0
(-10175 5750);
PAINT MONO (-10175 5750);
DISPLAY INVISIBLE (-10175 5750);
FORCEPROP 1 LAST PATH I28
J 0
(-10125 5900);
DISPLAY 0.978723 (-10125 5900);
PAINT WHITE (-10125 5900);
DISPLAY INVISIBLE (-10125 5900);
FORCEPROP 2 LAST $SEC 1
J 0
(-10125 5950);
DISPLAY 0.680851 (-10125 5950);
PAINT MONO (-10125 5950);
DISPLAY INVISIBLE (-10125 5950);
FORCEPROP 2 LAST CDS_SEC 1
J 0
(-10125 5950);
DISPLAY 1.021277 (-10125 5950);
DISPLAY INVISIBLE (-10125 5950);
FORCEADD UNIVERSAL_GND..1
(-10175 5500);
FORCEPROP 3 LASTPIN (-10175 5550) SIG_NAME GND\g
J 0
(-10165 5560);
DISPLAY 0.659574 (-10165 5560);
PAINT MONO (-10165 5560);
DISPLAY INVISIBLE (-10165 5560);
FORCEPROP 1 LAST HDL_POWER GND
J 1
(-10150 5425);
DISPLAY 0.872340 (-10150 5425);
PAINT GREEN (-10150 5425);
DISPLAY INVISIBLE (-10150 5425);
FORCEPROP 2 LAST CDS_LIB logical_power
J 0
(-10175 5500);
PAINT MONO (-10175 5500);
DISPLAY INVISIBLE (-10175 5500);
FORCEPROP 1 LAST PATH I29
J 0
(-10100 5500);
DISPLAY 0.872340 (-10100 5500);
PAINT AQUA (-10100 5500);
DISPLAY INVISIBLE (-10100 5500);
FORCEADD Q_RES..2
R 2
(-11200 1600);
FORCEPROP 1 LAST PART_NUMBER CS28872FB01
J 2
(-11250 1475);
DISPLAY 0.617021 (-11250 1475);
PAINT BLUE (-11250 1475);
DISPLAY INVISIBLE (-11250 1475);
FORCEPROP 1 LAST WATTAGE 1/16W
J 2
(-11250 1575);
DISPLAY 0.617021 (-11250 1575);
PAINT SKYBLUE (-11250 1575);
FORCEPROP 1 LAST PACK_TYPE 0402LF
J 2
(-11250 1425);
DISPLAY 0.617021 (-11250 1425);
PAINT SKYBLUE (-11250 1425);
FORCEPROP 1 LAST MATERIAL EMPTY
J 2
(-11250 1525);
DISPLAY 0.617021 (-11250 1525);
PAINT RED (-11250 1525);
FORCEPROP 1 LAST TOLERANCE 1%
J 2
(-11255 1625);
DISPLAY 0.617021 (-11255 1625);
PAINT SKYBLUE (-11255 1625);
FORCEPROP 1 LAST VALUE 8.87K
J 2
(-11255 1675);
DISPLAY 0.617021 (-11255 1675);
PAINT SKYBLUE (-11255 1675);
FORCEPROP 1 LAST LOCATION PR1297
J 2
(-11245 1725);
DISPLAY 0.617021 (-11245 1725);
PAINT AQUA (-11245 1725);
FORCEPROP 1 LASTPIN (-11200 1700) $PN 1
J 2
(-11205 1662);
DISPLAY 0.617021 (-11205 1662);
PAINT MONO (-11205 1662);
FORCEPROP 1 LASTPIN (-11200 1500) $PN 2
J 2
(-11205 1510);
DISPLAY 0.617021 (-11205 1510);
PAINT MONO (-11205 1510);
FORCEPROP 2 LAST CDS_LIB pure_quanta
J 2
(-11200 1600);
DISPLAY INVISIBLE (-11200 1600);
FORCEPROP 1 LAST PATH I3
J 2
(-11250 1775);
DISPLAY 0.978723 (-11250 1775);
PAINT WHITE (-11250 1775);
DISPLAY INVISIBLE (-11250 1775);
FORCEPROP 1 LAST LOCATION PR1297
J 2
(-11250 1775);
DISPLAY 1.021277 (-11250 1775);
PAINT AQUA (-11250 1775);
DISPLAY INVISIBLE (-11250 1775);
FORCEPROP 0 LAST $SEC 1
J 2
(-11250 1775);
DISPLAY 0.680851 (-11250 1775);
PAINT MONO (-11250 1775);
DISPLAY INVISIBLE (-11250 1775);
FORCEPROP 0 LAST CDS_SEC 1
J 2
(-11250 1775);
DISPLAY 1.021277 (-11250 1775);
DISPLAY INVISIBLE (-11250 1775);
FORCEADD UNIVERSAL_GND..1
(-8525 1375);
FORCEPROP 3 LASTPIN (-8525 1425) SIG_NAME GND\g
J 0
(-8515 1435);
DISPLAY 0.659574 (-8515 1435);
PAINT MONO (-8515 1435);
DISPLAY INVISIBLE (-8515 1435);
FORCEPROP 1 LAST HDL_POWER GND
J 1
(-8500 1300);
DISPLAY 0.872340 (-8500 1300);
PAINT GREEN (-8500 1300);
DISPLAY INVISIBLE (-8500 1300);
FORCEPROP 2 LAST CDS_LIB logical_power
J 0
(-8525 1375);
PAINT MONO (-8525 1375);
DISPLAY INVISIBLE (-8525 1375);
FORCEPROP 1 LAST PATH I30
J 0
(-8450 1375);
DISPLAY 0.872340 (-8450 1375);
PAINT AQUA (-8450 1375);
DISPLAY INVISIBLE (-8450 1375);
FORCEADD Q_CAP..1
(-8375 3000);
FORCEPROP 1 LAST PART_NUMBER TMP_QCH2336K1B12
J 0
(-8325 2850);
DISPLAY 0.617021 (-8325 2850);
PAINT BLUE (-8325 2850);
DISPLAY INVISIBLE (-8325 2850);
FORCEPROP 1 LAST VALUE 3300PF
J 0
(-8325 3100);
DISPLAY 0.617021 (-8325 3100);
PAINT SKYBLUE (-8325 3100);
FORCEPROP 1 LAST VOLTAGE 50V
J 0
(-8325 3050);
DISPLAY 0.617021 (-8325 3050);
PAINT SKYBLUE (-8325 3050);
FORCEPROP 1 LAST PACK_TYPE 0402
J 0
(-8325 2900);
DISPLAY 0.617021 (-8325 2900);
PAINT SKYBLUE (-8325 2900);
FORCEPROP 1 LAST TOLERANCE 10%
J 0
(-8325 3000);
DISPLAY 0.617021 (-8325 3000);
PAINT SKYBLUE (-8325 3000);
FORCEPROP 1 LAST MATERIAL X7R
J 0
(-8325 2950);
DISPLAY 0.617021 (-8325 2950);
PAINT RED (-8325 2950);
FORCEPROP 1 LAST LOCATION PC1174_P0_4
J 0
(-8325 3150);
DISPLAY 0.617021 (-8325 3150);
PAINT AQUA (-8325 3150);
FORCEPROP 1 LASTPIN (-8375 3100) $PN 1
J 0
(-8365 3080);
DISPLAY 0.617021 (-8365 3080);
PAINT MONO (-8365 3080);
FORCEPROP 1 LASTPIN (-8375 2900) $PN 2
J 0
(-8365 2880);
DISPLAY 0.617021 (-8365 2880);
PAINT MONO (-8365 2880);
FORCEPROP 2 LAST CDS_LIB pure_quanta
J 0
(-8375 3000);
DISPLAY INVISIBLE (-8375 3000);
FORCEPROP 1 LAST PATH I31
J 0
(-8325 3150);
DISPLAY 0.978723 (-8325 3150);
PAINT WHITE (-8325 3150);
DISPLAY INVISIBLE (-8325 3150);
FORCEPROP 1 LAST LOCATION PC1174_P0_4
J 0
(-8325 3200);
DISPLAY 1.021277 (-8325 3200);
PAINT AQUA (-8325 3200);
DISPLAY INVISIBLE (-8325 3200);
FORCEPROP 0 LAST $SEC 1
J 0
(-8325 3200);
DISPLAY 0.680851 (-8325 3200);
PAINT MONO (-8325 3200);
DISPLAY INVISIBLE (-8325 3200);
FORCEPROP 0 LAST CDS_SEC 1
J 0
(-8325 3200);
DISPLAY 1.021277 (-8325 3200);
DISPLAY INVISIBLE (-8325 3200);
FORCEADD UNIVERSAL_GND..1
(-8525 4175);
FORCEPROP 3 LASTPIN (-8525 4225) SIG_NAME GND\g
J 0
(-8515 4235);
DISPLAY 0.659574 (-8515 4235);
PAINT MONO (-8515 4235);
DISPLAY INVISIBLE (-8515 4235);
FORCEPROP 1 LAST HDL_POWER GND
J 1
(-8500 4100);
DISPLAY 0.872340 (-8500 4100);
PAINT GREEN (-8500 4100);
DISPLAY INVISIBLE (-8500 4100);
FORCEPROP 2 LAST CDS_LIB logical_power
J 0
(-8525 4175);
PAINT MONO (-8525 4175);
DISPLAY INVISIBLE (-8525 4175);
FORCEPROP 1 LAST PATH I32
J 0
(-8450 4175);
DISPLAY 0.872340 (-8450 4175);
PAINT AQUA (-8450 4175);
DISPLAY INVISIBLE (-8450 4175);
FORCEADD Q_RES..1
(-7675 2550);
FORCEPROP 1 LAST PART_NUMBER CS-3302FB01
J 0
(-7775 2600);
DISPLAY 0.617021 (-7775 2600);
PAINT BLUE (-7775 2600);
DISPLAY INVISIBLE (-7775 2600);
FORCEPROP 1 LAST VALUE 3.3
J 2
(-7450 2550);
DISPLAY 0.617021 (-7450 2550);
PAINT SKYBLUE (-7450 2550);
FORCEPROP 1 LAST PACK_TYPE 0402LF
J 0
(-7775 2625);
DISPLAY 0.617021 (-7775 2625);
PAINT SKYBLUE (-7775 2625);
FORCEPROP 1 LAST MATERIAL CHIP
J 0
(-7775 2650);
DISPLAY 0.617021 (-7775 2650);
PAINT RED (-7775 2650);
FORCEPROP 1 LAST WATTAGE 1/16W
J 2
(-7425 2625);
DISPLAY 0.617021 (-7425 2625);
PAINT SKYBLUE (-7425 2625);
FORCEPROP 1 LAST TOLERANCE 1%
J 0
(-7425 2550);
DISPLAY 0.617021 (-7425 2550);
PAINT SKYBLUE (-7425 2550);
FORCEPROP 1 LAST LOCATION PR1783
J 0
(-7925 2550);
DISPLAY 0.617021 (-7925 2550);
PAINT AQUA (-7925 2550);
FORCEPROP 1 LASTPIN (-7775 2550) $PN 1
J 0
(-7763 2562);
DISPLAY 0.617021 (-7763 2562);
FORCEPROP 1 LASTPIN (-7575 2550) $PN 2
J 0
(-7613 2562);
DISPLAY 0.617021 (-7613 2562);
FORCEPROP 2 LAST CDS_LIB pure_quanta
J 0
(-7675 2550);
PAINT MONO (-7675 2550);
DISPLAY INVISIBLE (-7675 2550);
FORCEPROP 1 LAST PATH I33
J 0
(-7725 2700);
DISPLAY 0.978723 (-7725 2700);
PAINT WHITE (-7725 2700);
DISPLAY INVISIBLE (-7725 2700);
FORCEPROP 2 LAST $SEC 1
J 0
(-7725 2750);
DISPLAY 0.680851 (-7725 2750);
PAINT MONO (-7725 2750);
DISPLAY INVISIBLE (-7725 2750);
FORCEPROP 2 LAST CDS_SEC 1
J 0
(-7725 2750);
DISPLAY 1.021277 (-7725 2750);
DISPLAY INVISIBLE (-7725 2750);
FORCEADD Q_CAP..1
(-7975 3000);
FORCEPROP 1 LAST PART_NUMBER CH5103KEB01
J 0
(-7925 2850);
DISPLAY 0.617021 (-7925 2850);
PAINT BLUE (-7925 2850);
DISPLAY INVISIBLE (-7925 2850);
FORCEPROP 1 LAST VALUE 1UF
J 0
(-7925 3100);
DISPLAY 0.617021 (-7925 3100);
PAINT SKYBLUE (-7925 3100);
FORCEPROP 1 LAST VOLTAGE 16V
J 0
(-7925 3050);
DISPLAY 0.617021 (-7925 3050);
PAINT SKYBLUE (-7925 3050);
FORCEPROP 1 LAST PACK_TYPE C0402
J 0
(-7925 2900);
DISPLAY 0.617021 (-7925 2900);
PAINT SKYBLUE (-7925 2900);
FORCEPROP 1 LAST MATERIAL X6S
J 0
(-7925 2950);
DISPLAY 0.617021 (-7925 2950);
PAINT RED (-7925 2950);
FORCEPROP 1 LAST TOLERANCE 10%
J 0
(-7925 3000);
DISPLAY 0.617021 (-7925 3000);
PAINT SKYBLUE (-7925 3000);
FORCEPROP 1 LAST LOCATION PC1176_P0_4
J 0
(-7925 3150);
DISPLAY 0.617021 (-7925 3150);
PAINT AQUA (-7925 3150);
FORCEPROP 1 LASTPIN (-7975 3100) $PN 1
J 0
(-7965 3080);
DISPLAY 0.617021 (-7965 3080);
PAINT MONO (-7965 3080);
FORCEPROP 1 LASTPIN (-7975 2900) $PN 2
J 0
(-7965 2880);
DISPLAY 0.617021 (-7965 2880);
PAINT MONO (-7965 2880);
FORCEPROP 2 LAST CDS_LIB pure_quanta
J 0
(-7975 3000);
DISPLAY INVISIBLE (-7975 3000);
FORCEPROP 1 LAST PATH I34
J 0
(-7925 3150);
DISPLAY 0.978723 (-7925 3150);
PAINT WHITE (-7925 3150);
DISPLAY INVISIBLE (-7925 3150);
FORCEPROP 1 LAST LOCATION PC1176_P0_4
J 0
(-7925 3200);
DISPLAY 1.021277 (-7925 3200);
PAINT AQUA (-7925 3200);
DISPLAY INVISIBLE (-7925 3200);
FORCEPROP 0 LAST $SEC 1
J 0
(-7925 3200);
DISPLAY 0.680851 (-7925 3200);
PAINT MONO (-7925 3200);
DISPLAY INVISIBLE (-7925 3200);
FORCEPROP 0 LAST CDS_SEC 1
J 0
(-7925 3200);
DISPLAY 1.021277 (-7925 3200);
DISPLAY INVISIBLE (-7925 3200);
FORCEADD Q_CAP..1
(-7575 3000);
FORCEPROP 1 LAST PART_NUMBER CH6223MEA01
J 0
(-7525 2850);
DISPLAY 0.617021 (-7525 2850);
PAINT BLUE (-7525 2850);
DISPLAY INVISIBLE (-7525 2850);
FORCEPROP 1 LAST TOLERANCE 20%
J 0
(-7525 3000);
DISPLAY 0.617021 (-7525 3000);
PAINT SKYBLUE (-7525 3000);
FORCEPROP 1 LAST PACK_TYPE C0805
J 0
(-7525 2900);
DISPLAY 0.617021 (-7525 2900);
PAINT SKYBLUE (-7525 2900);
FORCEPROP 1 LAST VALUE 22UF
J 0
(-7525 3100);
DISPLAY 0.617021 (-7525 3100);
PAINT SKYBLUE (-7525 3100);
FORCEPROP 1 LAST MATERIAL X6S
J 0
(-7525 2950);
DISPLAY 0.617021 (-7525 2950);
PAINT RED (-7525 2950);
FORCEPROP 1 LAST VOLTAGE 16V
J 0
(-7525 3050);
DISPLAY 0.617021 (-7525 3050);
PAINT SKYBLUE (-7525 3050);
FORCEPROP 1 LAST LOCATION PC1180_P0_4
J 0
(-7525 3150);
DISPLAY 0.617021 (-7525 3150);
PAINT AQUA (-7525 3150);
FORCEPROP 1 LASTPIN (-7575 3100) $PN 1
J 0
(-7565 3080);
DISPLAY 0.617021 (-7565 3080);
PAINT MONO (-7565 3080);
FORCEPROP 1 LASTPIN (-7575 2900) $PN 2
J 0
(-7565 2880);
DISPLAY 0.617021 (-7565 2880);
PAINT MONO (-7565 2880);
FORCEPROP 2 LAST CDS_LIB pure_quanta
J 0
(-7575 3000);
DISPLAY INVISIBLE (-7575 3000);
FORCEPROP 1 LAST PATH I35
J 0
(-7525 3150);
DISPLAY 0.978723 (-7525 3150);
PAINT WHITE (-7525 3150);
DISPLAY INVISIBLE (-7525 3150);
FORCEPROP 1 LAST LOCATION PC1180_P0_4
J 0
(-7525 3200);
DISPLAY 1.021277 (-7525 3200);
PAINT AQUA (-7525 3200);
DISPLAY INVISIBLE (-7525 3200);
FORCEPROP 0 LAST $SEC 1
J 0
(-7525 3200);
DISPLAY 0.680851 (-7525 3200);
PAINT MONO (-7525 3200);
DISPLAY INVISIBLE (-7525 3200);
FORCEPROP 0 LAST CDS_SEC 1
J 0
(-7525 3200);
DISPLAY 1.021277 (-7525 3200);
DISPLAY INVISIBLE (-7525 3200);
FORCEADD Q_CAP..1
(-7175 3000);
FORCEPROP 1 LAST PART_NUMBER CH6223MEA01
J 0
(-7125 2850);
DISPLAY 0.617021 (-7125 2850);
PAINT BLUE (-7125 2850);
DISPLAY INVISIBLE (-7125 2850);
FORCEPROP 1 LAST TOLERANCE 20%
J 0
(-7125 3000);
DISPLAY 0.617021 (-7125 3000);
PAINT SKYBLUE (-7125 3000);
FORCEPROP 1 LAST VOLTAGE 16V
J 0
(-7125 3050);
DISPLAY 0.617021 (-7125 3050);
PAINT SKYBLUE (-7125 3050);
FORCEPROP 1 LAST VALUE 22UF
J 0
(-7125 3100);
DISPLAY 0.617021 (-7125 3100);
PAINT SKYBLUE (-7125 3100);
FORCEPROP 1 LAST MATERIAL X6S
J 0
(-7125 2950);
DISPLAY 0.617021 (-7125 2950);
PAINT RED (-7125 2950);
FORCEPROP 1 LAST PACK_TYPE C0805
J 0
(-7125 2900);
DISPLAY 0.617021 (-7125 2900);
PAINT SKYBLUE (-7125 2900);
FORCEPROP 1 LAST LOCATION PC1182_P0_4
J 0
(-7125 3150);
DISPLAY 0.617021 (-7125 3150);
PAINT AQUA (-7125 3150);
FORCEPROP 1 LASTPIN (-7175 3100) $PN 1
J 0
(-7165 3080);
DISPLAY 0.617021 (-7165 3080);
PAINT MONO (-7165 3080);
FORCEPROP 1 LASTPIN (-7175 2900) $PN 2
J 0
(-7165 2880);
DISPLAY 0.617021 (-7165 2880);
PAINT MONO (-7165 2880);
FORCEPROP 2 LAST CDS_LIB pure_quanta
J 0
(-7175 3000);
DISPLAY INVISIBLE (-7175 3000);
FORCEPROP 1 LAST PATH I36
J 0
(-7125 3150);
DISPLAY 0.978723 (-7125 3150);
PAINT WHITE (-7125 3150);
DISPLAY INVISIBLE (-7125 3150);
FORCEPROP 1 LAST LOCATION PC1182_P0_4
J 0
(-7125 3200);
DISPLAY 1.021277 (-7125 3200);
PAINT AQUA (-7125 3200);
DISPLAY INVISIBLE (-7125 3200);
FORCEPROP 0 LAST $SEC 1
J 0
(-7125 3200);
DISPLAY 0.680851 (-7125 3200);
PAINT MONO (-7125 3200);
DISPLAY INVISIBLE (-7125 3200);
FORCEPROP 0 LAST CDS_SEC 1
J 0
(-7125 3200);
DISPLAY 1.021277 (-7125 3200);
DISPLAY INVISIBLE (-7125 3200);
FORCEADD Q_CAP..1
R 2
(-6750 2375);
FORCEPROP 1 LAST PART_NUMBER CH4106K1B01
J 2
(-6800 2300);
DISPLAY 0.617021 (-6800 2300);
PAINT BLUE (-6800 2300);
DISPLAY INVISIBLE (-6800 2300);
FORCEPROP 1 LAST TOLERANCE 10%
J 2
(-6800 2350);
DISPLAY 0.617021 (-6800 2350);
PAINT SKYBLUE (-6800 2350);
FORCEPROP 1 LAST VOLTAGE 50V
J 2
(-6800 2375);
DISPLAY 0.617021 (-6800 2375);
PAINT SKYBLUE (-6800 2375);
FORCEPROP 1 LAST MATERIAL X7R
J 2
(-6800 2325);
DISPLAY 0.617021 (-6800 2325);
PAINT RED (-6800 2325);
FORCEPROP 1 LAST VALUE 100NF
J 2
(-6800 2400);
DISPLAY 0.617021 (-6800 2400);
PAINT SKYBLUE (-6800 2400);
FORCEPROP 1 LAST PACK_TYPE C0402
J 2
(-6800 2275);
DISPLAY 0.617021 (-6800 2275);
PAINT SKYBLUE (-6800 2275);
FORCEPROP 1 LAST LOCATION PC1178
J 2
(-6800 2450);
DISPLAY 0.617021 (-6800 2450);
PAINT AQUA (-6800 2450);
FORCEPROP 1 LASTPIN (-6750 2475) $PN 1
J 2
(-6760 2455);
DISPLAY 0.617021 (-6760 2455);
FORCEPROP 1 LASTPIN (-6750 2275) $PN 2
J 2
(-6760 2255);
DISPLAY 0.617021 (-6760 2255);
FORCEPROP 2 LAST CDS_LIB pure_quanta
J 2
(-6750 2375);
PAINT MONO (-6750 2375);
DISPLAY INVISIBLE (-6750 2375);
FORCEPROP 1 LAST PATH I37
J 2
(-6800 2525);
DISPLAY 0.978723 (-6800 2525);
PAINT WHITE (-6800 2525);
DISPLAY INVISIBLE (-6800 2525);
FORCEPROP 2 LAST $SEC 1
J 0
(-6800 2575);
DISPLAY 0.680851 (-6800 2575);
PAINT MONO (-6800 2575);
DISPLAY INVISIBLE (-6800 2575);
FORCEPROP 2 LAST CDS_SEC 1
J 0
(-6800 2575);
DISPLAY 1.021277 (-6800 2575);
DISPLAY INVISIBLE (-6800 2575);
FORCEADD Q_RES..1
(-6475 1850);
FORCEPROP 1 LAST PART_NUMBER CS00002JB13
J 0
(-6575 1800);
DISPLAY 0.617021 (-6575 1800);
PAINT BLUE (-6575 1800);
DISPLAY INVISIBLE (-6575 1800);
FORCEPROP 1 LAST VALUE 0
J 2
(-6325 1850);
DISPLAY 0.617021 (-6325 1850);
PAINT SKYBLUE (-6325 1850);
FORCEPROP 1 LAST MATERIAL CHIP
J 0
(-6650 1750);
DISPLAY 0.617021 (-6650 1750);
PAINT RED (-6650 1750);
FORCEPROP 1 LAST WATTAGE 1/16W
J 2
(-6125 1750);
DISPLAY 0.617021 (-6125 1750);
PAINT SKYBLUE (-6125 1750);
FORCEPROP 1 LAST TOLERANCE 5%
J 0
(-6300 1850);
DISPLAY 0.617021 (-6300 1850);
PAINT SKYBLUE (-6300 1850);
FORCEPROP 1 LAST PACK_TYPE 0402LF
J 0
(-6475 1750);
DISPLAY 0.617021 (-6475 1750);
PAINT SKYBLUE (-6475 1750);
FORCEPROP 1 LAST LOCATION PR1325
J 0
(-6725 1850);
DISPLAY 0.617021 (-6725 1850);
PAINT AQUA (-6725 1850);
FORCEPROP 1 LASTPIN (-6575 1850) $PN 1
J 0
(-6563 1862);
DISPLAY 0.617021 (-6563 1862);
FORCEPROP 1 LASTPIN (-6375 1850) $PN 2
J 0
(-6413 1862);
DISPLAY 0.617021 (-6413 1862);
FORCEPROP 2 LAST CDS_LIB pure_quanta
J 0
(-6475 1850);
PAINT MONO (-6475 1850);
DISPLAY INVISIBLE (-6475 1850);
FORCEPROP 1 LAST PATH I38
J 0
(-6525 2000);
DISPLAY 0.978723 (-6525 2000);
PAINT WHITE (-6525 2000);
DISPLAY INVISIBLE (-6525 2000);
FORCEPROP 2 LAST $SEC 1
J 0
(-6525 2050);
DISPLAY 0.680851 (-6525 2050);
PAINT MONO (-6525 2050);
DISPLAY INVISIBLE (-6525 2050);
FORCEPROP 2 LAST CDS_SEC 1
J 0
(-6525 2050);
DISPLAY 1.021277 (-6525 2050);
DISPLAY INVISIBLE (-6525 2050);
FORCEADD Q_INDUCTOR..1
(-6475 2125);
FORCEPROP 1 LAST PART_NUMBER CV+13^0KZ11
J 0
(-6575 2060);
DISPLAY 0.617021 (-6575 2060);
PAINT BLUE (-6575 2060);
DISPLAY INVISIBLE (-6575 2060);
FORCEPROP 1 LAST MATERIAL IND
J 0
(-6575 2030);
DISPLAY 0.617021 (-6575 2030);
PAINT RED (-6575 2030);
FORCEPROP 2 LAST VALUE 130NH/106A
J 0
(-6300 2100);
DISPLAY 0.617021 (-6300 2100);
PAINT SKYBLUE (-6300 2100);
FORCEPROP 2 LAST PACK_TYPE SMLF
J 0
(-6300 2150);
DISPLAY 0.617021 (-6300 2150);
PAINT SKYBLUE (-6300 2150);
FORCEPROP 1 LAST LOCATION PL210
J 0
(-6750 2110);
DISPLAY 0.617021 (-6750 2110);
PAINT AQUA (-6750 2110);
FORCEPROP 2 LASTPIN (-6575 2100) $PN 1
J 2
(-6585 2110);
DISPLAY 0.617021 (-6585 2110);
FORCEPROP 2 LASTPIN (-6375 2100) $PN 2
J 0
(-6365 2110);
DISPLAY 0.617021 (-6365 2110);
FORCEPROP 1 LAST NEEDS_NO_SIZE TRUE
J 0
(-6475 2125);
DISPLAY 0.468085 (-6475 2125);
PAINT GREEN (-6475 2125);
DISPLAY INVISIBLE (-6475 2125);
FORCEPROP 2 LAST CDS_LIB pure_quanta
J 0
(-6475 2125);
PAINT MONO (-6475 2125);
DISPLAY INVISIBLE (-6475 2125);
FORCEPROP 1 LAST PATH I39
J 0
(-6400 2180);
DISPLAY 0.723404 (-6400 2180);
PAINT GREEN (-6400 2180);
DISPLAY INVISIBLE (-6400 2180);
FORCEPROP 2 LAST $SEC 1
J 0
(-6400 2225);
DISPLAY 0.680851 (-6400 2225);
PAINT MONO (-6400 2225);
DISPLAY INVISIBLE (-6400 2225);
FORCEPROP 2 LAST CDS_SEC 1
J 0
(-6400 2225);
DISPLAY 1.021277 (-6400 2225);
DISPLAY INVISIBLE (-6400 2225);
FORCEADD OFFPAGE..1
(-10725 1500);
FORCEPROP 2 LAST $XR0 266 
J 0
(-10977 1500);
DISPLAY 0.638298 (-10977 1500);
PAINT MONO (-10977 1500);
FORCEPROP 1 LAST COMMENT_BODY TRUE
J 0
(-10600 1400);
DISPLAY 0.872340 (-10600 1400);
PAINT GREEN (-10600 1400);
DISPLAY INVISIBLE (-10600 1400);
FORCEPROP 1 LAST OFFPAGE TRUE
J 0
(-10400 1375);
DISPLAY 0.872340 (-10400 1375);
PAINT GREEN (-10400 1375);
DISPLAY INVISIBLE (-10400 1375);
FORCEPROP 2 LAST CDS_LIB standard
J 0
(-10725 1500);
DISPLAY INVISIBLE (-10725 1500);
FORCEPROP 2 LAST PATH I4
J 0
(-10975 1550);
DISPLAY 1.021277 (-10975 1550);
DISPLAY INVISIBLE (-10975 1550);
FORCEADD Q_CAP..1
(-5450 1900);
FORCEPROP 1 LAST PART_NUMBER CH4106K1B01
J 0
(-5400 1775);
DISPLAY 0.617021 (-5400 1775);
PAINT BLUE (-5400 1775);
DISPLAY INVISIBLE (-5400 1775);
FORCEPROP 1 LAST PACK_TYPE C0402
J 0
(-5400 1725);
DISPLAY 0.617021 (-5400 1725);
PAINT SKYBLUE (-5400 1725);
FORCEPROP 1 LAST TOLERANCE 10%
J 0
(-5400 1875);
DISPLAY 0.617021 (-5400 1875);
PAINT SKYBLUE (-5400 1875);
FORCEPROP 1 LAST VOLTAGE 50V
J 0
(-5400 1925);
DISPLAY 0.617021 (-5400 1925);
PAINT SKYBLUE (-5400 1925);
FORCEPROP 1 LAST VALUE 100NF
J 0
(-5400 1975);
DISPLAY 0.617021 (-5400 1975);
PAINT SKYBLUE (-5400 1975);
FORCEPROP 1 LAST MATERIAL X7R
J 0
(-5400 1825);
DISPLAY 0.617021 (-5400 1825);
PAINT RED (-5400 1825);
FORCEPROP 1 LAST LOCATION PC1183_P0_4
J 0
(-5400 2025);
DISPLAY 0.617021 (-5400 2025);
PAINT AQUA (-5400 2025);
FORCEPROP 1 LASTPIN (-5450 2000) $PN 1
J 0
(-5440 1980);
DISPLAY 0.617021 (-5440 1980);
PAINT MONO (-5440 1980);
FORCEPROP 1 LASTPIN (-5450 1800) $PN 2
J 0
(-5440 1780);
DISPLAY 0.617021 (-5440 1780);
PAINT MONO (-5440 1780);
FORCEPROP 2 LAST CDS_LIB pure_quanta
J 0
(-5450 1900);
DISPLAY INVISIBLE (-5450 1900);
FORCEPROP 1 LAST PATH I40
J 0
(-5400 2050);
DISPLAY 0.978723 (-5400 2050);
PAINT WHITE (-5400 2050);
DISPLAY INVISIBLE (-5400 2050);
FORCEPROP 2 LAST $SEC 1
J 0
(-5400 2100);
DISPLAY 0.680851 (-5400 2100);
PAINT MONO (-5400 2100);
DISPLAY INVISIBLE (-5400 2100);
FORCEPROP 2 LAST CDS_SEC 1
J 0
(-5400 2100);
DISPLAY 1.021277 (-5400 2100);
DISPLAY INVISIBLE (-5400 2100);
FORCEADD Q_CAP..1
(-6725 3000);
FORCEPROP 1 LAST PART_NUMBER CH6223MEA01
J 0
(-6650 2850);
DISPLAY 0.617021 (-6650 2850);
PAINT BLUE (-6650 2850);
DISPLAY INVISIBLE (-6650 2850);
FORCEPROP 1 LAST TOLERANCE 20%
J 0
(-6650 3000);
DISPLAY 0.617021 (-6650 3000);
PAINT SKYBLUE (-6650 3000);
FORCEPROP 1 LAST MATERIAL X6S
J 0
(-6650 2950);
DISPLAY 0.617021 (-6650 2950);
PAINT RED (-6650 2950);
FORCEPROP 1 LAST PACK_TYPE C0805
J 0
(-6650 2900);
DISPLAY 0.617021 (-6650 2900);
PAINT SKYBLUE (-6650 2900);
FORCEPROP 1 LAST VALUE 22UF
J 0
(-6650 3100);
DISPLAY 0.617021 (-6650 3100);
PAINT SKYBLUE (-6650 3100);
FORCEPROP 1 LAST VOLTAGE 16V
J 0
(-6650 3050);
DISPLAY 0.617021 (-6650 3050);
PAINT SKYBLUE (-6650 3050);
FORCEPROP 1 LAST LOCATION PC723_P0_4
J 0
(-6650 3150);
DISPLAY 0.617021 (-6650 3150);
PAINT AQUA (-6650 3150);
FORCEPROP 1 LASTPIN (-6725 3100) $PN 1
J 0
(-6715 3080);
DISPLAY 0.787234 (-6715 3080);
PAINT MONO (-6715 3080);
FORCEPROP 1 LASTPIN (-6725 2900) $PN 2
J 0
(-6715 2880);
DISPLAY 0.787234 (-6715 2880);
PAINT MONO (-6715 2880);
FORCEPROP 2 LAST CDS_LIB pure_quanta
J 0
(-6725 3000);
DISPLAY INVISIBLE (-6725 3000);
FORCEPROP 1 LAST PATH I41
J 0
(-6675 3150);
DISPLAY 0.978723 (-6675 3150);
PAINT WHITE (-6675 3150);
DISPLAY INVISIBLE (-6675 3150);
FORCEPROP 0 LAST $SEC 1
J 0
(-6675 3150);
DISPLAY 0.680851 (-6675 3150);
PAINT MONO (-6675 3150);
DISPLAY INVISIBLE (-6675 3150);
FORCEPROP 0 LAST CDS_SEC 1
J 0
(-6675 3150);
DISPLAY 1.021277 (-6675 3150);
DISPLAY INVISIBLE (-6675 3150);
FORCEADD UNIVERSAL_GND..1
(-6575 2625);
FORCEPROP 3 LASTPIN (-6575 2675) SIG_NAME GND\g
J 0
(-6565 2685);
DISPLAY 0.659574 (-6565 2685);
PAINT MONO (-6565 2685);
DISPLAY INVISIBLE (-6565 2685);
FORCEPROP 1 LAST HDL_POWER GND
J 1
(-6550 2550);
DISPLAY 0.872340 (-6550 2550);
PAINT GREEN (-6550 2550);
DISPLAY INVISIBLE (-6550 2550);
FORCEPROP 2 LAST CDS_LIB logical_power
J 0
(-6575 2625);
PAINT MONO (-6575 2625);
DISPLAY INVISIBLE (-6575 2625);
FORCEPROP 1 LAST PATH I42
J 0
(-6500 2625);
DISPLAY 0.872340 (-6500 2625);
PAINT AQUA (-6500 2625);
DISPLAY INVISIBLE (-6500 2625);
FORCEADD VCC15..1
(-6575 3375);
FORCEPROP 3 LASTPIN (-6575 3325) SIG_NAME SW_P12V_PVCCFA_EHV_FIVRA_CPU0_L\g
J 0
(-6565 3335);
DISPLAY 0.659574 (-6565 3335);
PAINT MONO (-6565 3335);
DISPLAY INVISIBLE (-6565 3335);
FORCEPROP 1 LAST HDL_POWER SW_P12V_PVCCFA_EHV_FIVRA_CPU0_L
J 1
(-6525 3425);
DISPLAY 0.617021 (-6525 3425);
PAINT GREEN (-6525 3425);
FORCEPROP 2 LAST CDS_LIB logical_power
J 0
(-6575 3375);
DISPLAY INVISIBLE (-6575 3375);
FORCEPROP 1 LAST PATH I43
J 0
(-6525 3400);
DISPLAY 0.872340 (-6525 3400);
PAINT AQUA (-6525 3400);
DISPLAY INVISIBLE (-6525 3400);
FORCEADD Q_CAP..1
(-8375 5800);
FORCEPROP 1 LAST PART_NUMBER TMP_QCH2336K1B12
J 0
(-8325 5650);
DISPLAY 0.617021 (-8325 5650);
PAINT BLUE (-8325 5650);
DISPLAY INVISIBLE (-8325 5650);
FORCEPROP 1 LAST PACK_TYPE 0402
J 0
(-8325 5700);
DISPLAY 0.617021 (-8325 5700);
PAINT SKYBLUE (-8325 5700);
FORCEPROP 1 LAST TOLERANCE 10%
J 0
(-8325 5800);
DISPLAY 0.617021 (-8325 5800);
PAINT SKYBLUE (-8325 5800);
FORCEPROP 1 LAST MATERIAL X7R
J 0
(-8325 5750);
DISPLAY 0.617021 (-8325 5750);
PAINT RED (-8325 5750);
FORCEPROP 1 LAST VALUE 3300PF
J 0
(-8325 5900);
DISPLAY 0.617021 (-8325 5900);
PAINT SKYBLUE (-8325 5900);
FORCEPROP 1 LAST VOLTAGE 50V
J 0
(-8325 5850);
DISPLAY 0.617021 (-8325 5850);
PAINT SKYBLUE (-8325 5850);
FORCEPROP 1 LAST LOCATION PC1173_P0_3
J 0
(-8325 5950);
DISPLAY 0.617021 (-8325 5950);
PAINT AQUA (-8325 5950);
FORCEPROP 1 LASTPIN (-8375 5900) $PN 1
J 0
(-8365 5880);
DISPLAY 0.617021 (-8365 5880);
PAINT MONO (-8365 5880);
FORCEPROP 1 LASTPIN (-8375 5700) $PN 2
J 0
(-8365 5680);
DISPLAY 0.617021 (-8365 5680);
PAINT MONO (-8365 5680);
FORCEPROP 2 LAST CDS_LIB pure_quanta
J 0
(-8375 5800);
DISPLAY INVISIBLE (-8375 5800);
FORCEPROP 1 LAST PATH I44
J 0
(-8325 5950);
DISPLAY 0.978723 (-8325 5950);
PAINT WHITE (-8325 5950);
DISPLAY INVISIBLE (-8325 5950);
FORCEPROP 1 LAST LOCATION PC1173_P0_3
J 0
(-8325 6000);
DISPLAY 1.021277 (-8325 6000);
PAINT AQUA (-8325 6000);
DISPLAY INVISIBLE (-8325 6000);
FORCEPROP 0 LAST $SEC 1
J 0
(-8325 6000);
DISPLAY 0.680851 (-8325 6000);
PAINT MONO (-8325 6000);
DISPLAY INVISIBLE (-8325 6000);
FORCEPROP 0 LAST CDS_SEC 1
J 0
(-8325 6000);
DISPLAY 1.021277 (-8325 6000);
DISPLAY INVISIBLE (-8325 6000);
FORCEADD Q_RES..1
(-7675 5350);
FORCEPROP 1 LAST PART_NUMBER CS-3302FB01
J 0
(-7775 5400);
DISPLAY 0.617021 (-7775 5400);
PAINT BLUE (-7775 5400);
DISPLAY INVISIBLE (-7775 5400);
FORCEPROP 1 LAST PACK_TYPE 0402LF
J 0
(-7775 5425);
DISPLAY 0.617021 (-7775 5425);
PAINT SKYBLUE (-7775 5425);
FORCEPROP 1 LAST MATERIAL CHIP
J 0
(-7775 5450);
DISPLAY 0.617021 (-7775 5450);
PAINT RED (-7775 5450);
FORCEPROP 1 LAST TOLERANCE 1%
J 0
(-7425 5350);
DISPLAY 0.617021 (-7425 5350);
PAINT SKYBLUE (-7425 5350);
FORCEPROP 1 LAST VALUE 3.3
J 2
(-7450 5350);
DISPLAY 0.617021 (-7450 5350);
PAINT SKYBLUE (-7450 5350);
FORCEPROP 1 LAST WATTAGE 1/16W
J 2
(-7425 5425);
DISPLAY 0.617021 (-7425 5425);
PAINT SKYBLUE (-7425 5425);
FORCEPROP 1 LAST LOCATION PR1782
J 0
(-7925 5350);
DISPLAY 0.617021 (-7925 5350);
PAINT AQUA (-7925 5350);
FORCEPROP 1 LASTPIN (-7775 5350) $PN 1
J 0
(-7763 5362);
DISPLAY 0.617021 (-7763 5362);
FORCEPROP 1 LASTPIN (-7575 5350) $PN 2
J 0
(-7613 5362);
DISPLAY 0.617021 (-7613 5362);
FORCEPROP 2 LAST CDS_LIB pure_quanta
J 0
(-7675 5350);
PAINT MONO (-7675 5350);
DISPLAY INVISIBLE (-7675 5350);
FORCEPROP 1 LAST PATH I45
J 0
(-7725 5500);
DISPLAY 0.978723 (-7725 5500);
PAINT WHITE (-7725 5500);
DISPLAY INVISIBLE (-7725 5500);
FORCEPROP 2 LAST $SEC 1
J 0
(-7725 5550);
DISPLAY 0.680851 (-7725 5550);
PAINT MONO (-7725 5550);
DISPLAY INVISIBLE (-7725 5550);
FORCEPROP 2 LAST CDS_SEC 1
J 0
(-7725 5550);
DISPLAY 1.021277 (-7725 5550);
DISPLAY INVISIBLE (-7725 5550);
FORCEADD Q_CAP..1
(-7975 5800);
FORCEPROP 1 LAST PART_NUMBER CH5103KEB01
J 0
(-7925 5650);
DISPLAY 0.617021 (-7925 5650);
PAINT BLUE (-7925 5650);
DISPLAY INVISIBLE (-7925 5650);
FORCEPROP 1 LAST TOLERANCE 10%
J 0
(-7925 5800);
DISPLAY 0.617021 (-7925 5800);
PAINT SKYBLUE (-7925 5800);
FORCEPROP 1 LAST PACK_TYPE C0402
J 0
(-7925 5700);
DISPLAY 0.617021 (-7925 5700);
PAINT SKYBLUE (-7925 5700);
FORCEPROP 1 LAST VALUE 1UF
J 0
(-7925 5900);
DISPLAY 0.617021 (-7925 5900);
PAINT SKYBLUE (-7925 5900);
FORCEPROP 1 LAST MATERIAL X6S
J 0
(-7925 5750);
DISPLAY 0.617021 (-7925 5750);
PAINT RED (-7925 5750);
FORCEPROP 1 LAST VOLTAGE 16V
J 0
(-7925 5850);
DISPLAY 0.617021 (-7925 5850);
PAINT SKYBLUE (-7925 5850);
FORCEPROP 1 LAST LOCATION PC1175_P0_3
J 0
(-7925 5950);
DISPLAY 0.617021 (-7925 5950);
PAINT AQUA (-7925 5950);
FORCEPROP 1 LASTPIN (-7975 5900) $PN 1
J 0
(-7965 5880);
DISPLAY 0.617021 (-7965 5880);
PAINT MONO (-7965 5880);
FORCEPROP 1 LASTPIN (-7975 5700) $PN 2
J 0
(-7965 5680);
DISPLAY 0.617021 (-7965 5680);
PAINT MONO (-7965 5680);
FORCEPROP 2 LAST CDS_LIB pure_quanta
J 0
(-7975 5800);
DISPLAY INVISIBLE (-7975 5800);
FORCEPROP 1 LAST PATH I46
J 0
(-7925 5950);
DISPLAY 0.978723 (-7925 5950);
PAINT WHITE (-7925 5950);
DISPLAY INVISIBLE (-7925 5950);
FORCEPROP 1 LAST LOCATION PC1175_P0_3
J 0
(-7925 6000);
DISPLAY 1.021277 (-7925 6000);
PAINT AQUA (-7925 6000);
DISPLAY INVISIBLE (-7925 6000);
FORCEPROP 0 LAST $SEC 1
J 0
(-7925 6000);
DISPLAY 0.680851 (-7925 6000);
PAINT MONO (-7925 6000);
DISPLAY INVISIBLE (-7925 6000);
FORCEPROP 0 LAST CDS_SEC 1
J 0
(-7925 6000);
DISPLAY 1.021277 (-7925 6000);
DISPLAY INVISIBLE (-7925 6000);
FORCEADD Q_CAP..1
(-7575 5800);
FORCEPROP 1 LAST PART_NUMBER CH6223MEA01
J 0
(-7525 5650);
DISPLAY 0.617021 (-7525 5650);
PAINT BLUE (-7525 5650);
DISPLAY INVISIBLE (-7525 5650);
FORCEPROP 1 LAST TOLERANCE 20%
J 0
(-7525 5800);
DISPLAY 0.617021 (-7525 5800);
PAINT SKYBLUE (-7525 5800);
FORCEPROP 1 LAST PACK_TYPE C0805
J 0
(-7525 5700);
DISPLAY 0.617021 (-7525 5700);
PAINT SKYBLUE (-7525 5700);
FORCEPROP 1 LAST VOLTAGE 16V
J 0
(-7525 5850);
DISPLAY 0.617021 (-7525 5850);
PAINT SKYBLUE (-7525 5850);
FORCEPROP 1 LAST MATERIAL X6S
J 0
(-7525 5750);
DISPLAY 0.617021 (-7525 5750);
PAINT RED (-7525 5750);
FORCEPROP 1 LAST VALUE 22UF
J 0
(-7525 5900);
DISPLAY 0.617021 (-7525 5900);
PAINT SKYBLUE (-7525 5900);
FORCEPROP 1 LAST LOCATION PC1179_P0_3
J 0
(-7525 5950);
DISPLAY 0.617021 (-7525 5950);
PAINT AQUA (-7525 5950);
FORCEPROP 1 LASTPIN (-7575 5900) $PN 1
J 0
(-7565 5880);
DISPLAY 0.617021 (-7565 5880);
PAINT MONO (-7565 5880);
FORCEPROP 1 LASTPIN (-7575 5700) $PN 2
J 0
(-7565 5680);
DISPLAY 0.617021 (-7565 5680);
PAINT MONO (-7565 5680);
FORCEPROP 2 LAST CDS_LIB pure_quanta
J 0
(-7575 5800);
DISPLAY INVISIBLE (-7575 5800);
FORCEPROP 1 LAST PATH I47
J 0
(-7525 5950);
DISPLAY 0.978723 (-7525 5950);
PAINT WHITE (-7525 5950);
DISPLAY INVISIBLE (-7525 5950);
FORCEPROP 1 LAST LOCATION PC1179_P0_3
J 0
(-7525 6000);
DISPLAY 1.021277 (-7525 6000);
PAINT AQUA (-7525 6000);
DISPLAY INVISIBLE (-7525 6000);
FORCEPROP 0 LAST $SEC 1
J 0
(-7525 6000);
DISPLAY 0.680851 (-7525 6000);
PAINT MONO (-7525 6000);
DISPLAY INVISIBLE (-7525 6000);
FORCEPROP 0 LAST CDS_SEC 1
J 0
(-7525 6000);
DISPLAY 1.021277 (-7525 6000);
DISPLAY INVISIBLE (-7525 6000);
FORCEADD Q_CAP..1
(-7175 5800);
FORCEPROP 1 LAST PART_NUMBER CH6223MEA01
J 0
(-7125 5650);
DISPLAY 0.617021 (-7125 5650);
PAINT BLUE (-7125 5650);
DISPLAY INVISIBLE (-7125 5650);
FORCEPROP 1 LAST TOLERANCE 20%
J 0
(-7125 5800);
DISPLAY 0.617021 (-7125 5800);
PAINT SKYBLUE (-7125 5800);
FORCEPROP 1 LAST PACK_TYPE C0805
J 0
(-7125 5700);
DISPLAY 0.617021 (-7125 5700);
PAINT SKYBLUE (-7125 5700);
FORCEPROP 1 LAST MATERIAL X6S
J 0
(-7125 5750);
DISPLAY 0.617021 (-7125 5750);
PAINT RED (-7125 5750);
FORCEPROP 1 LAST VOLTAGE 16V
J 0
(-7125 5850);
DISPLAY 0.617021 (-7125 5850);
PAINT SKYBLUE (-7125 5850);
FORCEPROP 1 LAST VALUE 22UF
J 0
(-7125 5900);
DISPLAY 0.617021 (-7125 5900);
PAINT SKYBLUE (-7125 5900);
FORCEPROP 1 LAST LOCATION PC1181_P0_3
J 0
(-7125 5950);
DISPLAY 0.617021 (-7125 5950);
PAINT AQUA (-7125 5950);
FORCEPROP 1 LASTPIN (-7175 5900) $PN 1
J 0
(-7165 5880);
DISPLAY 0.617021 (-7165 5880);
PAINT MONO (-7165 5880);
FORCEPROP 1 LASTPIN (-7175 5700) $PN 2
J 0
(-7165 5680);
DISPLAY 0.617021 (-7165 5680);
PAINT MONO (-7165 5680);
FORCEPROP 2 LAST CDS_LIB pure_quanta
J 0
(-7175 5800);
DISPLAY INVISIBLE (-7175 5800);
FORCEPROP 1 LAST PATH I48
J 0
(-7125 5950);
DISPLAY 0.978723 (-7125 5950);
PAINT WHITE (-7125 5950);
DISPLAY INVISIBLE (-7125 5950);
FORCEPROP 1 LAST LOCATION PC1181_P0_3
J 0
(-7125 6000);
DISPLAY 1.021277 (-7125 6000);
PAINT AQUA (-7125 6000);
DISPLAY INVISIBLE (-7125 6000);
FORCEPROP 0 LAST $SEC 1
J 0
(-7125 6000);
DISPLAY 0.680851 (-7125 6000);
PAINT MONO (-7125 6000);
DISPLAY INVISIBLE (-7125 6000);
FORCEPROP 0 LAST CDS_SEC 1
J 0
(-7125 6000);
DISPLAY 1.021277 (-7125 6000);
DISPLAY INVISIBLE (-7125 6000);
FORCEADD Q_CAP..1
R 2
(-6750 5175);
FORCEPROP 1 LAST PART_NUMBER CH4106K1B01
J 2
(-6800 5125);
DISPLAY 0.617021 (-6800 5125);
PAINT BLUE (-6800 5125);
DISPLAY INVISIBLE (-6800 5125);
FORCEPROP 1 LAST PACK_TYPE C0402
J 2
(-6800 5100);
DISPLAY 0.617021 (-6800 5100);
PAINT SKYBLUE (-6800 5100);
FORCEPROP 1 LAST MATERIAL X7R
J 2
(-6800 5150);
DISPLAY 0.617021 (-6800 5150);
PAINT RED (-6800 5150);
FORCEPROP 1 LAST TOLERANCE 10%
J 2
(-6800 5175);
DISPLAY 0.617021 (-6800 5175);
PAINT SKYBLUE (-6800 5175);
FORCEPROP 1 LAST VOLTAGE 50V
J 2
(-6800 5200);
DISPLAY 0.617021 (-6800 5200);
PAINT SKYBLUE (-6800 5200);
FORCEPROP 1 LAST VALUE 100NF
J 2
(-6800 5225);
DISPLAY 0.617021 (-6800 5225);
PAINT SKYBLUE (-6800 5225);
FORCEPROP 1 LAST LOCATION PC1177
J 2
(-6800 5250);
DISPLAY 0.617021 (-6800 5250);
PAINT AQUA (-6800 5250);
FORCEPROP 1 LASTPIN (-6750 5275) $PN 1
J 2
(-6760 5255);
DISPLAY 0.617021 (-6760 5255);
FORCEPROP 1 LASTPIN (-6750 5075) $PN 2
J 2
(-6760 5055);
DISPLAY 0.617021 (-6760 5055);
FORCEPROP 2 LAST CDS_LIB pure_quanta
J 2
(-6750 5175);
PAINT MONO (-6750 5175);
DISPLAY INVISIBLE (-6750 5175);
FORCEPROP 1 LAST PATH I49
J 2
(-6800 5325);
DISPLAY 0.978723 (-6800 5325);
PAINT WHITE (-6800 5325);
DISPLAY INVISIBLE (-6800 5325);
FORCEPROP 2 LAST $SEC 1
J 0
(-6800 5375);
DISPLAY 0.680851 (-6800 5375);
PAINT MONO (-6800 5375);
DISPLAY INVISIBLE (-6800 5375);
FORCEPROP 2 LAST CDS_SEC 1
J 0
(-6800 5375);
DISPLAY 1.021277 (-6800 5375);
DISPLAY INVISIBLE (-6800 5375);
FORCEADD OFFPAGE..5
(-10725 1600);
FORCEPROP 2 LAST $XR2 266 
J 0
(-10980 1636);
DISPLAY 0.638298 (-10980 1636);
PAINT MONO (-10980 1636);
FORCEPROP 2 LAST $XR1 272 
J 0
(-10980 1564);
DISPLAY 0.638298 (-10980 1564);
PAINT MONO (-10980 1564);
FORCEPROP 2 LAST $XR0 271 
J 0
(-10980 1600);
DISPLAY 0.638298 (-10980 1600);
PAINT MONO (-10980 1600);
FORCEPROP 1 LAST COMMENT_BODY TRUE
J 0
(-10625 1525);
DISPLAY 0.872340 (-10625 1525);
PAINT GREEN (-10625 1525);
DISPLAY INVISIBLE (-10625 1525);
FORCEPROP 1 LAST OFFPAGE TRUE
J 0
(-10400 1475);
DISPLAY 0.872340 (-10400 1475);
PAINT GREEN (-10400 1475);
DISPLAY INVISIBLE (-10400 1475);
FORCEPROP 2 LAST CDS_LIB standard
J 0
(-10725 1600);
DISPLAY INVISIBLE (-10725 1600);
FORCEPROP 2 LAST PATH I5
J 0
(-10975 1675);
DISPLAY 1.021277 (-10975 1675);
DISPLAY INVISIBLE (-10975 1675);
FORCEADD Q_RES..1
(-6475 4650);
FORCEPROP 1 LAST PART_NUMBER CS00002JB13
J 0
(-6575 4600);
DISPLAY 0.617021 (-6575 4600);
PAINT BLUE (-6575 4600);
DISPLAY INVISIBLE (-6575 4600);
FORCEPROP 1 LAST TOLERANCE 5%
J 0
(-6300 4650);
DISPLAY 0.617021 (-6300 4650);
PAINT SKYBLUE (-6300 4650);
FORCEPROP 1 LAST VALUE 0
J 2
(-6325 4650);
DISPLAY 0.617021 (-6325 4650);
PAINT SKYBLUE (-6325 4650);
FORCEPROP 1 LAST WATTAGE 1/16W
J 2
(-6150 4550);
DISPLAY 0.617021 (-6150 4550);
PAINT SKYBLUE (-6150 4550);
FORCEPROP 1 LAST MATERIAL CHIP
J 0
(-6675 4550);
DISPLAY 0.617021 (-6675 4550);
PAINT RED (-6675 4550);
FORCEPROP 1 LAST PACK_TYPE 0402LF
J 0
(-6500 4550);
DISPLAY 0.617021 (-6500 4550);
PAINT SKYBLUE (-6500 4550);
FORCEPROP 1 LAST LOCATION PR1324
J 0
(-6725 4650);
DISPLAY 0.617021 (-6725 4650);
PAINT AQUA (-6725 4650);
FORCEPROP 1 LASTPIN (-6575 4650) $PN 1
J 0
(-6563 4662);
DISPLAY 0.617021 (-6563 4662);
FORCEPROP 1 LASTPIN (-6375 4650) $PN 2
J 0
(-6413 4662);
DISPLAY 0.617021 (-6413 4662);
FORCEPROP 2 LAST CDS_LIB pure_quanta
J 0
(-6475 4650);
PAINT MONO (-6475 4650);
DISPLAY INVISIBLE (-6475 4650);
FORCEPROP 1 LAST PATH I50
J 0
(-6525 4800);
DISPLAY 0.978723 (-6525 4800);
PAINT WHITE (-6525 4800);
DISPLAY INVISIBLE (-6525 4800);
FORCEPROP 2 LAST $SEC 1
J 0
(-6525 4850);
DISPLAY 0.680851 (-6525 4850);
PAINT MONO (-6525 4850);
DISPLAY INVISIBLE (-6525 4850);
FORCEPROP 2 LAST CDS_SEC 1
J 0
(-6525 4850);
DISPLAY 1.021277 (-6525 4850);
DISPLAY INVISIBLE (-6525 4850);
FORCEADD Q_INDUCTOR..1
(-6475 4925);
FORCEPROP 1 LAST PART_NUMBER CV+13^0KZ11
J 0
(-6600 5035);
DISPLAY 0.617021 (-6600 5035);
PAINT BLUE (-6600 5035);
DISPLAY INVISIBLE (-6600 5035);
FORCEPROP 2 LAST VALUE 130NH/106A
J 0
(-6600 5175);
DISPLAY 0.617021 (-6600 5175);
PAINT SKYBLUE (-6600 5175);
FORCEPROP 1 LAST MATERIAL IND
J 0
(-6600 4980);
DISPLAY 0.617021 (-6600 4980);
PAINT RED (-6600 4980);
FORCEPROP 2 LAST PACK_TYPE SMLF
J 0
(-6600 5125);
DISPLAY 0.617021 (-6600 5125);
PAINT SKYBLUE (-6600 5125);
FORCEPROP 1 LAST LOCATION PL2
J 0
(-6600 5085);
DISPLAY 0.617021 (-6600 5085);
PAINT AQUA (-6600 5085);
FORCEPROP 0 LASTPIN (-6575 4900) $PN 1
J 2
(-6585 4910);
DISPLAY 0.617021 (-6585 4910);
PAINT MONO (-6585 4910);
FORCEPROP 0 LASTPIN (-6375 4900) $PN 2
J 0
(-6365 4910);
DISPLAY 0.617021 (-6365 4910);
PAINT MONO (-6365 4910);
FORCEPROP 2 LAST CDS_LIB pure_quanta
J 0
(-6475 4925);
DISPLAY INVISIBLE (-6475 4925);
FORCEPROP 1 LAST NEEDS_NO_SIZE TRUE
J 0
(-6475 4925);
DISPLAY 0.468085 (-6475 4925);
PAINT GREEN (-6475 4925);
DISPLAY INVISIBLE (-6475 4925);
FORCEPROP 1 LAST PATH I51
J 0
(-6400 4980);
DISPLAY 0.723404 (-6400 4980);
PAINT GREEN (-6400 4980);
DISPLAY INVISIBLE (-6400 4980);
FORCEPROP 0 LAST $SEC 1
J 0
(-6600 5225);
DISPLAY 0.680851 (-6600 5225);
PAINT MONO (-6600 5225);
DISPLAY INVISIBLE (-6600 5225);
FORCEPROP 0 LAST CDS_SEC 1
J 0
(-6600 5225);
DISPLAY 1.021277 (-6600 5225);
DISPLAY INVISIBLE (-6600 5225);
FORCEADD UNIVERSAL_GND..1
(-6575 5425);
FORCEPROP 3 LASTPIN (-6575 5475) SIG_NAME GND\g
J 0
(-6565 5485);
DISPLAY 0.659574 (-6565 5485);
PAINT MONO (-6565 5485);
DISPLAY INVISIBLE (-6565 5485);
FORCEPROP 1 LAST HDL_POWER GND
J 1
(-6550 5350);
DISPLAY 0.872340 (-6550 5350);
PAINT GREEN (-6550 5350);
DISPLAY INVISIBLE (-6550 5350);
FORCEPROP 2 LAST CDS_LIB logical_power
J 0
(-6575 5425);
PAINT MONO (-6575 5425);
DISPLAY INVISIBLE (-6575 5425);
FORCEPROP 1 LAST PATH I52
J 0
(-6500 5425);
DISPLAY 0.872340 (-6500 5425);
PAINT AQUA (-6500 5425);
DISPLAY INVISIBLE (-6500 5425);
FORCEADD Q_CAP..1
(-6725 5800);
FORCEPROP 1 LAST PART_NUMBER CH6223MEA01
J 0
(-6650 5650);
DISPLAY 0.617021 (-6650 5650);
PAINT BLUE (-6650 5650);
DISPLAY INVISIBLE (-6650 5650);
FORCEPROP 1 LAST TOLERANCE 20%
J 0
(-6650 5800);
DISPLAY 0.617021 (-6650 5800);
PAINT SKYBLUE (-6650 5800);
FORCEPROP 1 LAST VALUE 22UF
J 0
(-6650 5900);
DISPLAY 0.617021 (-6650 5900);
PAINT SKYBLUE (-6650 5900);
FORCEPROP 1 LAST VOLTAGE 16V
J 0
(-6650 5850);
DISPLAY 0.617021 (-6650 5850);
PAINT SKYBLUE (-6650 5850);
FORCEPROP 1 LAST MATERIAL X6S
J 0
(-6650 5750);
DISPLAY 0.617021 (-6650 5750);
PAINT RED (-6650 5750);
FORCEPROP 1 LAST PACK_TYPE C0805
J 0
(-6650 5700);
DISPLAY 0.617021 (-6650 5700);
PAINT SKYBLUE (-6650 5700);
FORCEPROP 1 LAST LOCATION PC722_P0_3
J 0
(-6650 5950);
DISPLAY 0.617021 (-6650 5950);
PAINT AQUA (-6650 5950);
FORCEPROP 1 LASTPIN (-6725 5900) $PN 1
J 0
(-6715 5880);
DISPLAY 0.787234 (-6715 5880);
PAINT MONO (-6715 5880);
FORCEPROP 1 LASTPIN (-6725 5700) $PN 2
J 0
(-6715 5680);
DISPLAY 0.787234 (-6715 5680);
PAINT MONO (-6715 5680);
FORCEPROP 2 LAST CDS_LIB pure_quanta
J 0
(-6725 5800);
DISPLAY INVISIBLE (-6725 5800);
FORCEPROP 1 LAST PATH I53
J 0
(-6675 5950);
DISPLAY 0.978723 (-6675 5950);
PAINT WHITE (-6675 5950);
DISPLAY INVISIBLE (-6675 5950);
FORCEPROP 0 LAST $SEC 1
J 0
(-6675 5950);
DISPLAY 0.680851 (-6675 5950);
PAINT MONO (-6675 5950);
DISPLAY INVISIBLE (-6675 5950);
FORCEPROP 0 LAST CDS_SEC 1
J 0
(-6675 5950);
DISPLAY 1.021277 (-6675 5950);
DISPLAY INVISIBLE (-6675 5950);
FORCEADD VCC15..1
(-6575 6175);
FORCEPROP 3 LASTPIN (-6575 6125) SIG_NAME SW_P12V_PVCCFA_EHV_FIVRA_CPU0_R\g
J 0
(-6565 6135);
DISPLAY 0.659574 (-6565 6135);
PAINT MONO (-6565 6135);
DISPLAY INVISIBLE (-6565 6135);
FORCEPROP 1 LAST HDL_POWER SW_P12V_PVCCFA_EHV_FIVRA_CPU0_R
J 1
(-6525 6225);
DISPLAY 0.617021 (-6525 6225);
PAINT GREEN (-6525 6225);
FORCEPROP 2 LAST CDS_LIB logical_power
J 0
(-6575 6175);
DISPLAY INVISIBLE (-6575 6175);
FORCEPROP 1 LAST PATH I54
J 0
(-6525 6200);
DISPLAY 0.872340 (-6525 6200);
PAINT AQUA (-6525 6200);
DISPLAY INVISIBLE (-6525 6200);
FORCEADD Q_CAP..1
(-5425 4700);
FORCEPROP 1 LAST PART_NUMBER CH5103KEB01
J 0
(-5375 4525);
DISPLAY 0.617021 (-5375 4525);
PAINT BLUE (-5375 4525);
DISPLAY INVISIBLE (-5375 4525);
FORCEPROP 1 LAST VALUE 1UF
J 0
(-5375 4775);
DISPLAY 0.617021 (-5375 4775);
PAINT SKYBLUE (-5375 4775);
FORCEPROP 1 LAST PACK_TYPE C0402
J 0
(-5375 4575);
DISPLAY 0.617021 (-5375 4575);
PAINT SKYBLUE (-5375 4575);
FORCEPROP 1 LAST MATERIAL X6S
J 0
(-5375 4625);
DISPLAY 0.617021 (-5375 4625);
PAINT RED (-5375 4625);
FORCEPROP 1 LAST VOLTAGE 16V
J 0
(-5375 4725);
DISPLAY 0.617021 (-5375 4725);
PAINT SKYBLUE (-5375 4725);
FORCEPROP 1 LAST TOLERANCE 10%
J 0
(-5375 4675);
DISPLAY 0.617021 (-5375 4675);
PAINT SKYBLUE (-5375 4675);
FORCEPROP 1 LAST LOCATION PC1183_P0_3
J 0
(-5375 4825);
DISPLAY 0.617021 (-5375 4825);
PAINT AQUA (-5375 4825);
FORCEPROP 1 LASTPIN (-5425 4800) $PN 1
J 0
(-5415 4780);
DISPLAY 0.617021 (-5415 4780);
PAINT MONO (-5415 4780);
FORCEPROP 1 LASTPIN (-5425 4600) $PN 2
J 0
(-5415 4580);
DISPLAY 0.617021 (-5415 4580);
PAINT MONO (-5415 4580);
FORCEPROP 2 LAST CDS_LIB pure_quanta
J 0
(-5425 4700);
DISPLAY INVISIBLE (-5425 4700);
FORCEPROP 1 LAST PATH I55
J 0
(-5375 4850);
DISPLAY 0.978723 (-5375 4850);
PAINT WHITE (-5375 4850);
DISPLAY INVISIBLE (-5375 4850);
FORCEPROP 1 LAST LOCATION PC1183_P0_3
J 0
(-5375 4875);
DISPLAY 1.021277 (-5375 4875);
PAINT AQUA (-5375 4875);
DISPLAY INVISIBLE (-5375 4875);
FORCEPROP 0 LAST $SEC 1
J 0
(-5375 4875);
DISPLAY 0.680851 (-5375 4875);
PAINT MONO (-5375 4875);
DISPLAY INVISIBLE (-5375 4875);
FORCEPROP 0 LAST CDS_SEC 1
J 0
(-5375 4875);
DISPLAY 1.021277 (-5375 4875);
DISPLAY INVISIBLE (-5375 4875);
FORCEADD GND..1
(-5450 5325);
FORCEPROP 3 LASTPIN (-5450 5375) SIG_NAME GND\g
J 0
(-5440 5385);
DISPLAY 0.659574 (-5440 5385);
PAINT MONO (-5440 5385);
DISPLAY INVISIBLE (-5440 5385);
FORCEPROP 1 LAST HDL_POWER GND
J 0
(-5450 5475);
DISPLAY 0.872340 (-5450 5475);
PAINT GREEN (-5450 5475);
DISPLAY INVISIBLE (-5450 5475);
FORCEPROP 1 LAST SIZE 1B
J 0
(-5375 5275);
DISPLAY 0.872340 (-5375 5275);
PAINT AQUA (-5375 5275);
DISPLAY INVISIBLE (-5375 5275);
FORCEPROP 2 LAST CDS_LIB logical_power
J 0
(-5450 5325);
DISPLAY INVISIBLE (-5450 5325);
FORCEPROP 1 LAST PATH I56
J 0
(-5375 5325);
DISPLAY 0.872340 (-5375 5325);
PAINT AQUA (-5375 5325);
DISPLAY INVISIBLE (-5375 5325);
FORCEADD Q_CAP..1
(-5450 5575);
FORCEPROP 1 LAST PART_NUMBER CH4106K1B01
J 0
(-5400 5425);
DISPLAY 0.787234 (-5400 5425);
DISPLAY INVISIBLE (-5400 5425);
FORCEPROP 1 LAST PACK_TYPE C0402
J 0
(-5400 5375);
DISPLAY 0.787234 (-5400 5375);
FORCEPROP 1 LAST TOLERANCE 10%
J 0
(-5400 5525);
DISPLAY 0.787234 (-5400 5525);
FORCEPROP 1 LAST VOLTAGE 50V
J 0
(-5400 5575);
DISPLAY 0.787234 (-5400 5575);
FORCEPROP 1 LAST VALUE 100NF
J 0
(-5400 5625);
DISPLAY 0.787234 (-5400 5625);
FORCEPROP 1 LAST MATERIAL X7R
J 0
(-5400 5475);
DISPLAY 0.787234 (-5400 5475);
FORCEPROP 1 LAST LOCATION PC1654
J 0
(-5400 5675);
DISPLAY 0.787234 (-5400 5675);
FORCEPROP 1 LASTPIN (-5450 5675) $PN 1
J 0
(-5440 5655);
DISPLAY 0.787234 (-5440 5655);
PAINT MONO (-5440 5655);
FORCEPROP 1 LASTPIN (-5450 5475) $PN 2
J 0
(-5440 5455);
DISPLAY 0.787234 (-5440 5455);
PAINT MONO (-5440 5455);
FORCEPROP 2 LAST CDS_LIB pure_quanta
J 0
(-5450 5575);
DISPLAY INVISIBLE (-5450 5575);
FORCEPROP 1 LAST PATH I57
J 0
(-5400 5725);
DISPLAY 0.978723 (-5400 5725);
PAINT WHITE (-5400 5725);
DISPLAY INVISIBLE (-5400 5725);
FORCEPROP 0 LAST $SEC 1
J 0
(-5400 5725);
DISPLAY 0.680851 (-5400 5725);
PAINT MONO (-5400 5725);
DISPLAY INVISIBLE (-5400 5725);
FORCEPROP 0 LAST CDS_SEC 1
J 0
(-5400 5725);
DISPLAY 1.021277 (-5400 5725);
DISPLAY INVISIBLE (-5400 5725);
FORCEADD VCC15..1
(-5450 5950);
FORCEPROP 3 LASTPIN (-5450 5900) SIG_NAME P12V_AUX\g
J 0
(-5440 5910);
DISPLAY 0.659574 (-5440 5910);
PAINT MONO (-5440 5910);
DISPLAY INVISIBLE (-5440 5910);
FORCEPROP 1 LAST HDL_POWER P12V_AUX
J 1
(-5450 6000);
DISPLAY 0.617021 (-5450 6000);
PAINT GREEN (-5450 6000);
FORCEPROP 2 LAST CDS_LIB logical_power
J 0
(-5450 5950);
DISPLAY INVISIBLE (-5450 5950);
FORCEPROP 1 LAST PATH I58
J 0
(-5400 5975);
DISPLAY 0.872340 (-5400 5975);
PAINT AQUA (-5400 5975);
DISPLAY INVISIBLE (-5400 5975);
FORCEADD Q_INDUCTOR..1
(-5025 5800);
FORCEPROP 1 LAST PART_NUMBER CV+10G0MZ04
J 0
(-5125 5550);
DISPLAY 0.617021 (-5125 5550);
PAINT BLUE (-5125 5550);
DISPLAY INVISIBLE (-5125 5550);
FORCEPROP 2 LAST PACK_TYPE SMLF
J 0
(-5125 5650);
DISPLAY 0.617021 (-5125 5650);
PAINT SKYBLUE (-5125 5650);
FORCEPROP 1 LAST MATERIAL IND
J 0
(-5125 5600);
DISPLAY 0.617021 (-5125 5600);
PAINT SKYBLUE (-5125 5600);
FORCEPROP 2 LAST VALUE 100NH/16A
J 0
(-5125 5700);
DISPLAY 0.617021 (-5125 5700);
PAINT SKYBLUE (-5125 5700);
FORCEPROP 1 LAST LOCATION PL101
J 0
(-5325 5785);
DISPLAY 0.617021 (-5325 5785);
PAINT AQUA (-5325 5785);
FORCEPROP 2 LASTPIN (-5125 5775) $PN 1
J 2
(-5135 5785);
DISPLAY 0.617021 (-5135 5785);
FORCEPROP 2 LASTPIN (-4925 5775) $PN 2
J 0
(-4915 5785);
DISPLAY 0.617021 (-4915 5785);
FORCEPROP 2 LAST CDS_LIB pure_quanta
J 0
(-5025 5800);
PAINT MONO (-5025 5800);
DISPLAY INVISIBLE (-5025 5800);
FORCEPROP 1 LAST NEEDS_NO_SIZE TRUE
J 0
(-5025 5800);
DISPLAY 0.468085 (-5025 5800);
PAINT GREEN (-5025 5800);
DISPLAY INVISIBLE (-5025 5800);
FORCEPROP 1 LAST PATH I59
J 0
(-4950 5855);
DISPLAY 0.723404 (-4950 5855);
PAINT GREEN (-4950 5855);
DISPLAY INVISIBLE (-4950 5855);
FORCEPROP 2 LAST $SEC 1
J 0
(-4950 5900);
DISPLAY 0.680851 (-4950 5900);
PAINT MONO (-4950 5900);
DISPLAY INVISIBLE (-4950 5900);
FORCEPROP 2 LAST CDS_SEC 1
J 0
(-4950 5900);
DISPLAY 1.021277 (-4950 5900);
DISPLAY INVISIBLE (-4950 5900);
FORCEADD OFFPAGE..1
(-10725 2000);
FORCEPROP 2 LAST $XR6 272 
J 0
(-11697 2000);
DISPLAY 0.638298 (-11697 2000);
PAINT MONO (-11697 2000);
FORCEPROP 2 LAST $XR5 271 
J 0
(-11577 2000);
DISPLAY 0.638298 (-11577 2000);
PAINT MONO (-11577 2000);
FORCEPROP 2 LAST $XR4 270 
J 0
(-11457 2000);
DISPLAY 0.638298 (-11457 2000);
PAINT MONO (-11457 2000);
FORCEPROP 2 LAST $XR3 269 
J 0
(-11337 2000);
DISPLAY 0.638298 (-11337 2000);
PAINT MONO (-11337 2000);
FORCEPROP 2 LAST $XR2 268 
J 0
(-11217 2000);
DISPLAY 0.638298 (-11217 2000);
PAINT MONO (-11217 2000);
FORCEPROP 2 LAST $XR1 267 
J 0
(-11097 2000);
DISPLAY 0.638298 (-11097 2000);
PAINT MONO (-11097 2000);
FORCEPROP 2 LAST $XR0 266 
J 0
(-10977 2000);
DISPLAY 0.638298 (-10977 2000);
PAINT MONO (-10977 2000);
FORCEPROP 1 LAST COMMENT_BODY TRUE
J 0
(-10600 1900);
DISPLAY 0.872340 (-10600 1900);
PAINT GREEN (-10600 1900);
DISPLAY INVISIBLE (-10600 1900);
FORCEPROP 1 LAST OFFPAGE TRUE
J 0
(-10400 1875);
DISPLAY 0.872340 (-10400 1875);
PAINT GREEN (-10400 1875);
DISPLAY INVISIBLE (-10400 1875);
FORCEPROP 2 LAST CDS_LIB standard
J 0
(-10725 2000);
DISPLAY INVISIBLE (-10725 2000);
FORCEPROP 2 LAST PATH I6
J 0
(-10975 2050);
DISPLAY 1.021277 (-10975 2050);
DISPLAY INVISIBLE (-10975 2050);
FORCEADD Q_CAP..1
(-5000 1900);
FORCEPROP 1 LAST PART_NUMBER CH622KMEA03
J 0
(-4950 1725);
DISPLAY 0.617021 (-4950 1725);
PAINT BLUE (-4950 1725);
DISPLAY INVISIBLE (-4950 1725);
FORCEPROP 1 LAST TOLERANCE 20%
J 0
(-4950 1875);
DISPLAY 0.617021 (-4950 1875);
PAINT SKYBLUE (-4950 1875);
FORCEPROP 1 LAST VOLTAGE 4V
J 0
(-4950 1925);
DISPLAY 0.617021 (-4950 1925);
PAINT SKYBLUE (-4950 1925);
FORCEPROP 1 LAST VALUE 22UF
J 0
(-4950 1975);
DISPLAY 0.617021 (-4950 1975);
PAINT SKYBLUE (-4950 1975);
FORCEPROP 1 LAST PACK_TYPE C0805
J 0
(-4950 1775);
DISPLAY 0.617021 (-4950 1775);
PAINT SKYBLUE (-4950 1775);
FORCEPROP 1 LAST MATERIAL X6S
J 0
(-4950 1825);
DISPLAY 0.617021 (-4950 1825);
PAINT RED (-4950 1825);
FORCEPROP 1 LAST LOCATION PC1186_P0_4
J 0
(-4950 2025);
DISPLAY 0.617021 (-4950 2025);
PAINT AQUA (-4950 2025);
FORCEPROP 1 LASTPIN (-5000 2000) $PN 1
J 0
(-4990 1980);
DISPLAY 0.617021 (-4990 1980);
PAINT MONO (-4990 1980);
FORCEPROP 1 LASTPIN (-5000 1800) $PN 2
J 0
(-4990 1780);
DISPLAY 0.617021 (-4990 1780);
PAINT MONO (-4990 1780);
FORCEPROP 2 LAST CDS_LIB pure_quanta
J 0
(-5000 1900);
DISPLAY INVISIBLE (-5000 1900);
FORCEPROP 1 LAST PATH I60
J 0
(-4950 2050);
DISPLAY 0.978723 (-4950 2050);
PAINT WHITE (-4950 2050);
DISPLAY INVISIBLE (-4950 2050);
FORCEPROP 1 LAST LOCATION PC1186_P0_4
J 0
(-4950 2075);
DISPLAY 1.021277 (-4950 2075);
PAINT AQUA (-4950 2075);
DISPLAY INVISIBLE (-4950 2075);
FORCEPROP 0 LAST $SEC 1
J 0
(-4950 2075);
DISPLAY 0.680851 (-4950 2075);
PAINT MONO (-4950 2075);
DISPLAY INVISIBLE (-4950 2075);
FORCEPROP 0 LAST CDS_SEC 1
J 0
(-4950 2075);
DISPLAY 1.021277 (-4950 2075);
DISPLAY INVISIBLE (-4950 2075);
FORCEADD Q_CAP..1
(-4575 1900);
FORCEPROP 1 LAST PART_NUMBER CH622KMEA03
J 0
(-4525 1725);
DISPLAY 0.617021 (-4525 1725);
PAINT BLUE (-4525 1725);
DISPLAY INVISIBLE (-4525 1725);
FORCEPROP 1 LAST TOLERANCE 20%
J 0
(-4525 1875);
DISPLAY 0.617021 (-4525 1875);
PAINT SKYBLUE (-4525 1875);
FORCEPROP 1 LAST MATERIAL X6S
J 0
(-4525 1825);
DISPLAY 0.617021 (-4525 1825);
PAINT RED (-4525 1825);
FORCEPROP 1 LAST VOLTAGE 4V
J 0
(-4525 1925);
DISPLAY 0.617021 (-4525 1925);
PAINT SKYBLUE (-4525 1925);
FORCEPROP 1 LAST VALUE 22UF
J 0
(-4525 1975);
DISPLAY 0.617021 (-4525 1975);
PAINT SKYBLUE (-4525 1975);
FORCEPROP 1 LAST PACK_TYPE C0805
J 0
(-4525 1775);
DISPLAY 0.617021 (-4525 1775);
PAINT SKYBLUE (-4525 1775);
FORCEPROP 1 LAST LOCATION PC1188_P0_4
J 0
(-4525 2025);
DISPLAY 0.617021 (-4525 2025);
PAINT AQUA (-4525 2025);
FORCEPROP 1 LASTPIN (-4575 2000) $PN 1
J 0
(-4565 1980);
DISPLAY 0.617021 (-4565 1980);
PAINT MONO (-4565 1980);
FORCEPROP 1 LASTPIN (-4575 1800) $PN 2
J 0
(-4565 1780);
DISPLAY 0.617021 (-4565 1780);
PAINT MONO (-4565 1780);
FORCEPROP 2 LAST CDS_LIB pure_quanta
J 0
(-4575 1900);
DISPLAY INVISIBLE (-4575 1900);
FORCEPROP 1 LAST PATH I61
J 0
(-4525 2050);
DISPLAY 0.978723 (-4525 2050);
PAINT WHITE (-4525 2050);
DISPLAY INVISIBLE (-4525 2050);
FORCEPROP 1 LAST LOCATION PC1188_P0_4
J 0
(-4525 2075);
DISPLAY 1.021277 (-4525 2075);
PAINT AQUA (-4525 2075);
DISPLAY INVISIBLE (-4525 2075);
FORCEPROP 0 LAST $SEC 1
J 0
(-4525 2075);
DISPLAY 0.680851 (-4525 2075);
PAINT MONO (-4525 2075);
DISPLAY INVISIBLE (-4525 2075);
FORCEPROP 0 LAST CDS_SEC 1
J 0
(-4525 2075);
DISPLAY 1.021277 (-4525 2075);
DISPLAY INVISIBLE (-4525 2075);
FORCEADD UNIVERSAL_GND..1
(-4275 1525);
FORCEPROP 3 LASTPIN (-4275 1575) SIG_NAME GND\g
J 0
(-4265 1585);
DISPLAY 0.659574 (-4265 1585);
PAINT MONO (-4265 1585);
DISPLAY INVISIBLE (-4265 1585);
FORCEPROP 1 LAST HDL_POWER GND
J 1
(-4250 1450);
DISPLAY 0.872340 (-4250 1450);
PAINT GREEN (-4250 1450);
DISPLAY INVISIBLE (-4250 1450);
FORCEPROP 2 LAST CDS_LIB logical_power
J 0
(-4275 1525);
PAINT MONO (-4275 1525);
DISPLAY INVISIBLE (-4275 1525);
FORCEPROP 1 LAST PATH I62
J 0
(-4200 1525);
DISPLAY 0.872340 (-4200 1525);
PAINT AQUA (-4200 1525);
DISPLAY INVISIBLE (-4200 1525);
FORCEADD VCC15..1
(-4275 2300);
FORCEPROP 3 LASTPIN (-4275 2250) SIG_NAME PVCCFA_EHV_FIVRA_CPU0\g
J 0
(-4265 2260);
DISPLAY 0.659574 (-4265 2260);
PAINT MONO (-4265 2260);
DISPLAY INVISIBLE (-4265 2260);
FORCEPROP 1 LAST HDL_POWER PVCCFA_EHV_FIVRA_CPU0
J 1
(-4275 2350);
DISPLAY 0.617021 (-4275 2350);
PAINT GREEN (-4275 2350);
FORCEPROP 2 LAST CDS_LIB logical_power
J 0
(-4275 2300);
DISPLAY INVISIBLE (-4275 2300);
FORCEPROP 1 LAST PATH I63
J 0
(-4225 2325);
DISPLAY 0.872340 (-4225 2325);
PAINT AQUA (-4225 2325);
DISPLAY INVISIBLE (-4225 2325);
FORCEADD Q_CAPP..1
(-5025 3500);
FORCEPROP 1 LAST PART_NUMBER CC7560JMD16
J 0
(-4950 3350);
DISPLAY 0.617021 (-4950 3350);
PAINT BLUE (-4950 3350);
DISPLAY INVISIBLE (-4950 3350);
FORCEPROP 1 LAST PACK_TYPE THLF
J 0
(-4950 3400);
DISPLAY 0.617021 (-4950 3400);
PAINT SKYBLUE (-4950 3400);
FORCEPROP 1 LAST VALUE 560UF
J 0
(-4950 3600);
DISPLAY 0.617021 (-4950 3600);
PAINT SKYBLUE (-4950 3600);
FORCEPROP 1 LAST TOLERANCE 20%
J 0
(-4950 3550);
DISPLAY 0.617021 (-4950 3550);
PAINT SKYBLUE (-4950 3550);
FORCEPROP 1 LAST MATERIAL OSCON
J 0
(-4950 3450);
DISPLAY 0.617021 (-4950 3450);
PAINT SKYBLUE (-4950 3450);
FORCEPROP 1 LAST VOLTAGE 2.5V
J 0
(-4950 3500);
DISPLAY 0.617021 (-4950 3500);
PAINT SKYBLUE (-4950 3500);
FORCEPROP 1 LAST LOCATION PC1183
J 0
(-4950 3650);
DISPLAY 0.617021 (-4950 3650);
PAINT AQUA (-4950 3650);
FORCEPROP 1 LASTPIN (-5025 3600) $PN 1
J 0
(-5015 3585);
DISPLAY 0.617021 (-5015 3585);
PAINT MONO (-5015 3585);
FORCEPROP 1 LASTPIN (-5025 3400) $PN 2
J 0
(-5015 3385);
DISPLAY 0.617021 (-5015 3385);
PAINT MONO (-5015 3385);
FORCEPROP 2 LAST CDS_LIB pure_quanta
J 0
(-5025 3500);
DISPLAY INVISIBLE (-5025 3500);
FORCEPROP 1 LAST PATH I64
J 0
(-4975 3650);
DISPLAY 0.978723 (-4975 3650);
DISPLAY INVISIBLE (-4975 3650);
FORCEPROP 2 LAST $SEC 1
J 0
(-4950 3700);
DISPLAY 0.680851 (-4950 3700);
PAINT MONO (-4950 3700);
DISPLAY INVISIBLE (-4950 3700);
FORCEPROP 2 LAST CDS_SEC 1
J 0
(-4950 3700);
DISPLAY 1.021277 (-4950 3700);
DISPLAY INVISIBLE (-4950 3700);
FORCEADD Q_CAPP..1
(-4500 3500);
FORCEPROP 1 LAST PART_NUMBER CC7560JMD16
J 0
(-4425 3350);
DISPLAY 0.617021 (-4425 3350);
PAINT BLUE (-4425 3350);
DISPLAY INVISIBLE (-4425 3350);
FORCEPROP 1 LAST PACK_TYPE THLF
J 0
(-4425 3400);
DISPLAY 0.617021 (-4425 3400);
PAINT SKYBLUE (-4425 3400);
FORCEPROP 1 LAST VALUE 560UF
J 0
(-4425 3600);
DISPLAY 0.617021 (-4425 3600);
PAINT SKYBLUE (-4425 3600);
FORCEPROP 1 LAST TOLERANCE 20%
J 0
(-4425 3550);
DISPLAY 0.617021 (-4425 3550);
PAINT SKYBLUE (-4425 3550);
FORCEPROP 1 LAST MATERIAL OSCON
J 0
(-4425 3450);
DISPLAY 0.617021 (-4425 3450);
PAINT SKYBLUE (-4425 3450);
FORCEPROP 1 LAST VOLTAGE 2.5V
J 0
(-4425 3500);
DISPLAY 0.617021 (-4425 3500);
PAINT SKYBLUE (-4425 3500);
FORCEPROP 1 LAST LOCATION PC1185
J 0
(-4450 3650);
DISPLAY 0.617021 (-4450 3650);
PAINT AQUA (-4450 3650);
FORCEPROP 1 LASTPIN (-4500 3600) $PN 1
J 0
(-4490 3585);
DISPLAY 0.617021 (-4490 3585);
PAINT MONO (-4490 3585);
FORCEPROP 1 LASTPIN (-4500 3400) $PN 2
J 0
(-4490 3385);
DISPLAY 0.617021 (-4490 3385);
PAINT MONO (-4490 3385);
FORCEPROP 2 LAST CDS_LIB pure_quanta
J 0
(-4500 3500);
DISPLAY INVISIBLE (-4500 3500);
FORCEPROP 1 LAST PATH I65
J 0
(-4450 3650);
DISPLAY 0.978723 (-4450 3650);
DISPLAY INVISIBLE (-4450 3650);
FORCEPROP 2 LAST $SEC 1
J 0
(-4450 3700);
DISPLAY 0.680851 (-4450 3700);
PAINT MONO (-4450 3700);
DISPLAY INVISIBLE (-4450 3700);
FORCEPROP 2 LAST CDS_SEC 1
J 0
(-4450 3700);
DISPLAY 1.021277 (-4450 3700);
DISPLAY INVISIBLE (-4450 3700);
FORCEADD UNIVERSAL_GND..1
(-4275 4325);
FORCEPROP 3 LASTPIN (-4275 4375) SIG_NAME GND\g
J 0
(-4265 4385);
DISPLAY 0.659574 (-4265 4385);
PAINT MONO (-4265 4385);
DISPLAY INVISIBLE (-4265 4385);
FORCEPROP 1 LAST HDL_POWER GND
J 1
(-4250 4250);
DISPLAY 0.872340 (-4250 4250);
PAINT GREEN (-4250 4250);
DISPLAY INVISIBLE (-4250 4250);
FORCEPROP 2 LAST CDS_LIB logical_power
J 0
(-4275 4325);
PAINT MONO (-4275 4325);
DISPLAY INVISIBLE (-4275 4325);
FORCEPROP 1 LAST PATH I66
J 0
(-4200 4325);
DISPLAY 0.872340 (-4200 4325);
PAINT AQUA (-4200 4325);
DISPLAY INVISIBLE (-4200 4325);
FORCEADD UNIVERSAL_GND..1
(-3025 3150);
FORCEPROP 3 LASTPIN (-3025 3200) SIG_NAME GND\g
J 0
(-3015 3210);
DISPLAY 0.659574 (-3015 3210);
PAINT MONO (-3015 3210);
DISPLAY INVISIBLE (-3015 3210);
FORCEPROP 1 LAST HDL_POWER GND
J 1
(-3000 3075);
DISPLAY 0.872340 (-3000 3075);
PAINT GREEN (-3000 3075);
DISPLAY INVISIBLE (-3000 3075);
FORCEPROP 2 LAST CDS_LIB logical_power
J 0
(-3025 3150);
PAINT MONO (-3025 3150);
DISPLAY INVISIBLE (-3025 3150);
FORCEPROP 1 LAST PATH I67
J 0
(-2950 3150);
DISPLAY 0.872340 (-2950 3150);
PAINT AQUA (-2950 3150);
DISPLAY INVISIBLE (-2950 3150);
FORCEADD Q_CAPP..1
(-3975 3500);
FORCEPROP 1 LAST PART_NUMBER CC7560JMD16
J 0
(-3900 3350);
DISPLAY 0.617021 (-3900 3350);
PAINT BLUE (-3900 3350);
DISPLAY INVISIBLE (-3900 3350);
FORCEPROP 1 LAST PACK_TYPE THLF
J 0
(-3900 3400);
DISPLAY 0.617021 (-3900 3400);
PAINT SKYBLUE (-3900 3400);
FORCEPROP 1 LAST VALUE 560UF
J 0
(-3900 3600);
DISPLAY 0.617021 (-3900 3600);
PAINT SKYBLUE (-3900 3600);
FORCEPROP 1 LAST TOLERANCE 20%
J 0
(-3900 3550);
DISPLAY 0.617021 (-3900 3550);
PAINT SKYBLUE (-3900 3550);
FORCEPROP 1 LAST MATERIAL OSCON
J 0
(-3900 3450);
DISPLAY 0.617021 (-3900 3450);
PAINT RED (-3900 3450);
FORCEPROP 1 LAST VOLTAGE 2.5V
J 0
(-3900 3500);
DISPLAY 0.617021 (-3900 3500);
PAINT SKYBLUE (-3900 3500);
FORCEPROP 1 LAST LOCATION PC1186
J 0
(-3925 3650);
DISPLAY 0.617021 (-3925 3650);
PAINT AQUA (-3925 3650);
FORCEPROP 1 LASTPIN (-3975 3600) $PN 1
J 0
(-3965 3585);
DISPLAY 0.617021 (-3965 3585);
PAINT MONO (-3965 3585);
FORCEPROP 1 LASTPIN (-3975 3400) $PN 2
J 0
(-3965 3385);
DISPLAY 0.617021 (-3965 3385);
PAINT MONO (-3965 3385);
FORCEPROP 2 LAST CDS_LIB pure_quanta
J 0
(-3975 3500);
DISPLAY INVISIBLE (-3975 3500);
FORCEPROP 1 LAST PATH I68
J 0
(-3925 3650);
DISPLAY 0.978723 (-3925 3650);
DISPLAY INVISIBLE (-3925 3650);
FORCEPROP 2 LAST $SEC 1
J 0
(-3925 3700);
DISPLAY 0.680851 (-3925 3700);
PAINT MONO (-3925 3700);
DISPLAY INVISIBLE (-3925 3700);
FORCEPROP 2 LAST CDS_SEC 1
J 0
(-3925 3700);
DISPLAY 1.021277 (-3925 3700);
DISPLAY INVISIBLE (-3925 3700);
FORCEADD Q_CAPP..1
(-3475 3500);
FORCEPROP 1 LAST PART_NUMBER CH733LY8802
J 0
(-3400 3350);
DISPLAY 0.617021 (-3400 3350);
PAINT BLUE (-3400 3350);
DISPLAY INVISIBLE (-3400 3350);
FORCEPROP 1 LAST VOLTAGE 2.5V
J 0
(-3400 3500);
DISPLAY 0.617021 (-3400 3500);
PAINT SKYBLUE (-3400 3500);
FORCEPROP 1 LAST TOLERANCE +10/-35%
J 0
(-3400 3550);
DISPLAY 0.617021 (-3400 3550);
PAINT SKYBLUE (-3400 3550);
FORCEPROP 1 LAST VALUE 330UF
J 0
(-3400 3600);
DISPLAY 0.617021 (-3400 3600);
PAINT SKYBLUE (-3400 3600);
FORCEPROP 1 LAST PACK_TYPE SMLF
J 0
(-3400 3400);
DISPLAY 0.617021 (-3400 3400);
PAINT SKYBLUE (-3400 3400);
FORCEPROP 1 LAST MATERIAL SPCAP
J 0
(-3400 3450);
DISPLAY 0.617021 (-3400 3450);
PAINT SKYBLUE (-3400 3450);
FORCEPROP 1 LAST LOCATION PC1187
J 0
(-3425 3650);
DISPLAY 0.617021 (-3425 3650);
PAINT AQUA (-3425 3650);
FORCEPROP 1 LASTPIN (-3475 3600) $PN 1
J 0
(-3465 3585);
DISPLAY 0.617021 (-3465 3585);
PAINT MONO (-3465 3585);
FORCEPROP 1 LASTPIN (-3475 3400) $PN 2
J 0
(-3465 3385);
DISPLAY 0.617021 (-3465 3385);
PAINT MONO (-3465 3385);
FORCEPROP 2 LAST CDS_LIB pure_quanta
J 0
(-3475 3500);
DISPLAY INVISIBLE (-3475 3500);
FORCEPROP 1 LAST PATH I69
J 0
(-3425 3650);
DISPLAY 0.978723 (-3425 3650);
DISPLAY INVISIBLE (-3425 3650);
FORCEPROP 2 LAST $SEC 1
J 0
(-3425 3700);
DISPLAY 0.680851 (-3425 3700);
PAINT MONO (-3425 3700);
DISPLAY INVISIBLE (-3425 3700);
FORCEPROP 2 LAST CDS_SEC 1
J 0
(-3425 3700);
DISPLAY 1.021277 (-3425 3700);
DISPLAY INVISIBLE (-3425 3700);
FORCEADD OFFPAGE..5
(-10725 2100);
FORCEPROP 2 LAST $XR0 266 
J 0
(-10980 2100);
DISPLAY 0.638298 (-10980 2100);
PAINT MONO (-10980 2100);
FORCEPROP 1 LAST COMMENT_BODY TRUE
J 0
(-10625 2025);
DISPLAY 0.872340 (-10625 2025);
PAINT GREEN (-10625 2025);
DISPLAY INVISIBLE (-10625 2025);
FORCEPROP 1 LAST OFFPAGE TRUE
J 0
(-10400 1975);
DISPLAY 0.872340 (-10400 1975);
PAINT GREEN (-10400 1975);
DISPLAY INVISIBLE (-10400 1975);
FORCEPROP 2 LAST CDS_LIB standard
J 0
(-10725 2100);
DISPLAY INVISIBLE (-10725 2100);
FORCEPROP 2 LAST PATH I7
J 0
(-10975 2150);
DISPLAY 1.021277 (-10975 2150);
DISPLAY INVISIBLE (-10975 2150);
FORCEADD Q_CAPP..1
(-3025 3500);
FORCEPROP 1 LAST PART_NUMBER CH733LY8802
J 0
(-2950 3350);
DISPLAY 0.617021 (-2950 3350);
PAINT BLUE (-2950 3350);
DISPLAY INVISIBLE (-2950 3350);
FORCEPROP 1 LAST VOLTAGE 2.5V
J 0
(-2950 3500);
DISPLAY 0.617021 (-2950 3500);
PAINT SKYBLUE (-2950 3500);
FORCEPROP 1 LAST TOLERANCE +10/-35%
J 0
(-2950 3550);
DISPLAY 0.617021 (-2950 3550);
PAINT SKYBLUE (-2950 3550);
FORCEPROP 1 LAST VALUE 330UF
J 0
(-2950 3600);
DISPLAY 0.617021 (-2950 3600);
PAINT SKYBLUE (-2950 3600);
FORCEPROP 1 LAST PACK_TYPE SMLF
J 0
(-2950 3400);
DISPLAY 0.617021 (-2950 3400);
PAINT SKYBLUE (-2950 3400);
FORCEPROP 1 LAST MATERIAL SPCAP
J 0
(-2950 3450);
DISPLAY 0.617021 (-2950 3450);
PAINT RED (-2950 3450);
FORCEPROP 1 LAST LOCATION PC2170
J 0
(-2950 3650);
DISPLAY 0.617021 (-2950 3650);
PAINT AQUA (-2950 3650);
FORCEPROP 1 LASTPIN (-3025 3600) $PN 1
J 0
(-3015 3585);
DISPLAY 0.617021 (-3015 3585);
PAINT MONO (-3015 3585);
FORCEPROP 1 LASTPIN (-3025 3400) $PN 2
J 0
(-3015 3385);
DISPLAY 0.617021 (-3015 3385);
PAINT MONO (-3015 3385);
FORCEPROP 2 LAST CDS_LIB pure_quanta
J 0
(-3025 3500);
DISPLAY INVISIBLE (-3025 3500);
FORCEPROP 1 LAST PATH I70
J 0
(-2975 3650);
DISPLAY 0.978723 (-2975 3650);
DISPLAY INVISIBLE (-2975 3650);
FORCEPROP 2 LAST $SEC 1
J 0
(-2975 3700);
DISPLAY 0.680851 (-2975 3700);
PAINT MONO (-2975 3700);
DISPLAY INVISIBLE (-2975 3700);
FORCEPROP 2 LAST CDS_SEC 1
J 0
(-2975 3700);
DISPLAY 1.021277 (-2975 3700);
DISPLAY INVISIBLE (-2975 3700);
FORCEADD VCC15..1
(-3025 3825);
FORCEPROP 3 LASTPIN (-3025 3775) SIG_NAME PVCCFA_EHV_FIVRA_CPU0\g
J 0
(-3015 3785);
DISPLAY 0.659574 (-3015 3785);
PAINT MONO (-3015 3785);
DISPLAY INVISIBLE (-3015 3785);
FORCEPROP 1 LAST HDL_POWER PVCCFA_EHV_FIVRA_CPU0
J 1
(-3025 3875);
DISPLAY 0.617021 (-3025 3875);
PAINT GREEN (-3025 3875);
FORCEPROP 2 LAST CDS_LIB logical_power
J 0
(-3025 3825);
DISPLAY INVISIBLE (-3025 3825);
FORCEPROP 1 LAST PATH I71
J 0
(-2975 3850);
DISPLAY 0.872340 (-2975 3850);
PAINT AQUA (-2975 3850);
DISPLAY INVISIBLE (-2975 3850);
FORCEADD Q_CAP..1
(-5000 4700);
FORCEPROP 1 LAST PART_NUMBER CH622KMEA03
J 0
(-4950 4525);
DISPLAY 0.617021 (-4950 4525);
PAINT BLUE (-4950 4525);
DISPLAY INVISIBLE (-4950 4525);
FORCEPROP 1 LAST TOLERANCE 20%
J 0
(-4950 4675);
DISPLAY 0.617021 (-4950 4675);
PAINT SKYBLUE (-4950 4675);
FORCEPROP 1 LAST MATERIAL X6S
J 0
(-4950 4625);
DISPLAY 0.617021 (-4950 4625);
PAINT RED (-4950 4625);
FORCEPROP 1 LAST VALUE 22UF
J 0
(-4950 4775);
DISPLAY 0.617021 (-4950 4775);
PAINT SKYBLUE (-4950 4775);
FORCEPROP 1 LAST PACK_TYPE C0805
J 0
(-4950 4575);
DISPLAY 0.617021 (-4950 4575);
PAINT SKYBLUE (-4950 4575);
FORCEPROP 1 LAST VOLTAGE 4V
J 0
(-4950 4725);
DISPLAY 0.617021 (-4950 4725);
PAINT SKYBLUE (-4950 4725);
FORCEPROP 1 LAST LOCATION PC1185_P0_3
J 0
(-4950 4825);
DISPLAY 0.617021 (-4950 4825);
PAINT AQUA (-4950 4825);
FORCEPROP 1 LASTPIN (-5000 4800) $PN 1
J 0
(-4990 4780);
DISPLAY 0.617021 (-4990 4780);
PAINT MONO (-4990 4780);
FORCEPROP 1 LASTPIN (-5000 4600) $PN 2
J 0
(-4990 4580);
DISPLAY 0.617021 (-4990 4580);
PAINT MONO (-4990 4580);
FORCEPROP 2 LAST CDS_LIB pure_quanta
J 0
(-5000 4700);
DISPLAY INVISIBLE (-5000 4700);
FORCEPROP 1 LAST PATH I72
J 0
(-4950 4850);
DISPLAY 0.978723 (-4950 4850);
PAINT WHITE (-4950 4850);
DISPLAY INVISIBLE (-4950 4850);
FORCEPROP 1 LAST LOCATION PC1185_P0_3
J 0
(-4950 4875);
DISPLAY 1.021277 (-4950 4875);
PAINT AQUA (-4950 4875);
DISPLAY INVISIBLE (-4950 4875);
FORCEPROP 0 LAST $SEC 1
J 0
(-4950 4875);
DISPLAY 0.680851 (-4950 4875);
PAINT MONO (-4950 4875);
DISPLAY INVISIBLE (-4950 4875);
FORCEPROP 0 LAST CDS_SEC 1
J 0
(-4950 4875);
DISPLAY 1.021277 (-4950 4875);
DISPLAY INVISIBLE (-4950 4875);
FORCEADD Q_CAP..1
(-4575 4700);
FORCEPROP 1 LAST PART_NUMBER CH622KMEA03
J 0
(-4525 4525);
DISPLAY 0.617021 (-4525 4525);
PAINT BLUE (-4525 4525);
DISPLAY INVISIBLE (-4525 4525);
FORCEPROP 1 LAST TOLERANCE 20%
J 0
(-4525 4675);
DISPLAY 0.617021 (-4525 4675);
PAINT SKYBLUE (-4525 4675);
FORCEPROP 1 LAST MATERIAL X6S
J 0
(-4525 4625);
DISPLAY 0.617021 (-4525 4625);
PAINT RED (-4525 4625);
FORCEPROP 1 LAST VOLTAGE 4V
J 0
(-4525 4725);
DISPLAY 0.617021 (-4525 4725);
PAINT SKYBLUE (-4525 4725);
FORCEPROP 1 LAST PACK_TYPE C0805
J 0
(-4525 4575);
DISPLAY 0.617021 (-4525 4575);
PAINT SKYBLUE (-4525 4575);
FORCEPROP 1 LAST VALUE 22UF
J 0
(-4525 4775);
DISPLAY 0.617021 (-4525 4775);
PAINT SKYBLUE (-4525 4775);
FORCEPROP 1 LAST LOCATION PC1187_P0_3
J 0
(-4525 4825);
DISPLAY 0.617021 (-4525 4825);
PAINT AQUA (-4525 4825);
FORCEPROP 1 LASTPIN (-4575 4800) $PN 1
J 0
(-4565 4780);
DISPLAY 0.617021 (-4565 4780);
PAINT MONO (-4565 4780);
FORCEPROP 1 LASTPIN (-4575 4600) $PN 2
J 0
(-4565 4580);
DISPLAY 0.617021 (-4565 4580);
PAINT MONO (-4565 4580);
FORCEPROP 2 LAST CDS_LIB pure_quanta
J 0
(-4575 4700);
DISPLAY INVISIBLE (-4575 4700);
FORCEPROP 1 LAST PATH I73
J 0
(-4525 4850);
DISPLAY 0.978723 (-4525 4850);
PAINT WHITE (-4525 4850);
DISPLAY INVISIBLE (-4525 4850);
FORCEPROP 1 LAST LOCATION PC1187_P0_3
J 0
(-4525 4875);
DISPLAY 1.021277 (-4525 4875);
PAINT AQUA (-4525 4875);
DISPLAY INVISIBLE (-4525 4875);
FORCEPROP 0 LAST $SEC 1
J 0
(-4525 4875);
DISPLAY 0.680851 (-4525 4875);
PAINT MONO (-4525 4875);
DISPLAY INVISIBLE (-4525 4875);
FORCEPROP 0 LAST CDS_SEC 1
J 0
(-4525 4875);
DISPLAY 1.021277 (-4525 4875);
DISPLAY INVISIBLE (-4525 4875);
FORCEADD VCC15..1
(-4275 5100);
FORCEPROP 3 LASTPIN (-4275 5050) SIG_NAME PVCCFA_EHV_FIVRA_CPU0\g
J 0
(-4265 5060);
DISPLAY 0.659574 (-4265 5060);
PAINT MONO (-4265 5060);
DISPLAY INVISIBLE (-4265 5060);
FORCEPROP 1 LAST HDL_POWER PVCCFA_EHV_FIVRA_CPU0
J 1
(-4275 5150);
DISPLAY 0.617021 (-4275 5150);
PAINT GREEN (-4275 5150);
FORCEPROP 2 LAST CDS_LIB logical_power
J 0
(-4275 5100);
DISPLAY INVISIBLE (-4275 5100);
FORCEPROP 1 LAST PATH I74
J 0
(-4225 5125);
DISPLAY 0.872340 (-4225 5125);
PAINT AQUA (-4225 5125);
DISPLAY INVISIBLE (-4225 5125);
FORCEADD Q_CAP..1
(-4625 5550);
FORCEPROP 1 LAST PART_NUMBER CH6223MEA01
J 0
(-4575 5425);
DISPLAY 0.404255 (-4575 5425);
DISPLAY INVISIBLE (-4575 5425);
FORCEPROP 1 LAST TOLERANCE 20%
J 0
(-4575 5525);
DISPLAY 0.510638 (-4575 5525);
FORCEPROP 1 LAST PACK_TYPE C0805
J 0
(-4575 5375);
DISPLAY 0.510638 (-4575 5375);
FORCEPROP 1 LAST VOLTAGE 16V
J 0
(-4575 5575);
DISPLAY 0.510638 (-4575 5575);
FORCEPROP 1 LAST VALUE 22UF
J 0
(-4575 5625);
DISPLAY 0.510638 (-4575 5625);
FORCEPROP 1 LAST MATERIAL X6S
J 0
(-4575 5475);
DISPLAY 0.510638 (-4575 5475);
FORCEPROP 1 LAST LOCATION PC1673
J 0
(-4575 5675);
DISPLAY 0.510638 (-4575 5675);
FORCEPROP 1 LASTPIN (-4625 5650) $PN 1
J 0
(-4615 5630);
DISPLAY 0.787234 (-4615 5630);
PAINT MONO (-4615 5630);
FORCEPROP 1 LASTPIN (-4625 5450) $PN 2
J 0
(-4615 5430);
DISPLAY 0.787234 (-4615 5430);
PAINT MONO (-4615 5430);
FORCEPROP 2 LAST CDS_LIB pure_quanta
J 0
(-4625 5550);
DISPLAY INVISIBLE (-4625 5550);
FORCEPROP 1 LAST PATH I75
J 0
(-4575 5700);
DISPLAY 0.978723 (-4575 5700);
PAINT WHITE (-4575 5700);
DISPLAY INVISIBLE (-4575 5700);
FORCEPROP 0 LAST $SEC 1
J 0
(-4575 5700);
DISPLAY 0.680851 (-4575 5700);
PAINT MONO (-4575 5700);
DISPLAY INVISIBLE (-4575 5700);
FORCEPROP 0 LAST CDS_SEC 1
J 0
(-4575 5700);
DISPLAY 1.021277 (-4575 5700);
DISPLAY INVISIBLE (-4575 5700);
FORCEADD Q_CAP..1
(-4325 5550);
FORCEPROP 1 LAST PART_NUMBER CH6223MEA01
J 0
(-4275 5425);
DISPLAY 0.404255 (-4275 5425);
DISPLAY INVISIBLE (-4275 5425);
FORCEPROP 1 LAST TOLERANCE 20%
J 0
(-4275 5525);
DISPLAY 0.510638 (-4275 5525);
FORCEPROP 1 LAST MATERIAL X6S
J 0
(-4275 5475);
DISPLAY 0.510638 (-4275 5475);
FORCEPROP 1 LAST VOLTAGE 16V
J 0
(-4275 5575);
DISPLAY 0.510638 (-4275 5575);
FORCEPROP 1 LAST VALUE 22UF
J 0
(-4275 5625);
DISPLAY 0.510638 (-4275 5625);
FORCEPROP 1 LAST PACK_TYPE C0805
J 0
(-4275 5375);
DISPLAY 0.510638 (-4275 5375);
FORCEPROP 1 LAST LOCATION PC1674
J 0
(-4275 5675);
DISPLAY 0.510638 (-4275 5675);
FORCEPROP 1 LASTPIN (-4325 5650) $PN 1
J 0
(-4315 5630);
DISPLAY 0.787234 (-4315 5630);
PAINT MONO (-4315 5630);
FORCEPROP 1 LASTPIN (-4325 5450) $PN 2
J 0
(-4315 5430);
DISPLAY 0.787234 (-4315 5430);
PAINT MONO (-4315 5430);
FORCEPROP 2 LAST CDS_LIB pure_quanta
J 0
(-4325 5550);
DISPLAY INVISIBLE (-4325 5550);
FORCEPROP 1 LAST PATH I76
J 0
(-4275 5700);
DISPLAY 0.978723 (-4275 5700);
PAINT WHITE (-4275 5700);
DISPLAY INVISIBLE (-4275 5700);
FORCEPROP 0 LAST $SEC 1
J 0
(-4275 5700);
DISPLAY 0.680851 (-4275 5700);
PAINT MONO (-4275 5700);
DISPLAY INVISIBLE (-4275 5700);
FORCEPROP 0 LAST CDS_SEC 1
J 0
(-4275 5700);
DISPLAY 1.021277 (-4275 5700);
DISPLAY INVISIBLE (-4275 5700);
FORCEADD Q_CAP..1
(-4050 5550);
FORCEPROP 1 LAST PART_NUMBER CH6223MEA01
J 0
(-4000 5425);
DISPLAY 0.404255 (-4000 5425);
DISPLAY INVISIBLE (-4000 5425);
FORCEPROP 1 LAST TOLERANCE 20%
J 0
(-4000 5525);
DISPLAY 0.510638 (-4000 5525);
FORCEPROP 1 LAST MATERIAL X6S
J 0
(-4000 5475);
DISPLAY 0.510638 (-4000 5475);
FORCEPROP 1 LAST VOLTAGE 16V
J 0
(-4000 5575);
DISPLAY 0.510638 (-4000 5575);
FORCEPROP 1 LAST PACK_TYPE C0805
J 0
(-4000 5375);
DISPLAY 0.510638 (-4000 5375);
FORCEPROP 1 LAST VALUE 22UF
J 0
(-4000 5625);
DISPLAY 0.510638 (-4000 5625);
FORCEPROP 1 LAST LOCATION PC1675
J 0
(-4000 5675);
DISPLAY 0.510638 (-4000 5675);
FORCEPROP 1 LASTPIN (-4050 5650) $PN 1
J 0
(-4040 5630);
DISPLAY 0.787234 (-4040 5630);
PAINT MONO (-4040 5630);
FORCEPROP 1 LASTPIN (-4050 5450) $PN 2
J 0
(-4040 5430);
DISPLAY 0.787234 (-4040 5430);
PAINT MONO (-4040 5430);
FORCEPROP 2 LAST CDS_LIB pure_quanta
J 0
(-4050 5550);
DISPLAY INVISIBLE (-4050 5550);
FORCEPROP 1 LAST PATH I77
J 0
(-4000 5700);
DISPLAY 0.978723 (-4000 5700);
PAINT WHITE (-4000 5700);
DISPLAY INVISIBLE (-4000 5700);
FORCEPROP 0 LAST $SEC 1
J 0
(-4000 5700);
DISPLAY 0.680851 (-4000 5700);
PAINT MONO (-4000 5700);
DISPLAY INVISIBLE (-4000 5700);
FORCEPROP 0 LAST CDS_SEC 1
J 0
(-4000 5700);
DISPLAY 1.021277 (-4000 5700);
DISPLAY INVISIBLE (-4000 5700);
FORCEADD UNIVERSAL_GND..1
(-3500 5250);
FORCEPROP 3 LASTPIN (-3500 5300) SIG_NAME GND\g
J 0
(-3490 5310);
DISPLAY 0.659574 (-3490 5310);
PAINT MONO (-3490 5310);
DISPLAY INVISIBLE (-3490 5310);
FORCEPROP 1 LAST HDL_POWER GND
J 1
(-3475 5175);
DISPLAY 0.872340 (-3475 5175);
PAINT GREEN (-3475 5175);
DISPLAY INVISIBLE (-3475 5175);
FORCEPROP 2 LAST CDS_LIB logical_power
J 0
(-3500 5250);
PAINT MONO (-3500 5250);
DISPLAY INVISIBLE (-3500 5250);
FORCEPROP 1 LAST PATH I78
J 0
(-3425 5250);
DISPLAY 0.872340 (-3425 5250);
PAINT AQUA (-3425 5250);
DISPLAY INVISIBLE (-3425 5250);
FORCEADD Q_CAP..1
(-3775 5550);
FORCEPROP 1 LAST PART_NUMBER CH6223MEA01
J 0
(-3725 5425);
DISPLAY 0.404255 (-3725 5425);
DISPLAY INVISIBLE (-3725 5425);
FORCEPROP 1 LAST TOLERANCE 20%
J 0
(-3725 5525);
DISPLAY 0.510638 (-3725 5525);
FORCEPROP 1 LAST MATERIAL X6S
J 0
(-3725 5475);
DISPLAY 0.510638 (-3725 5475);
FORCEPROP 1 LAST VALUE 22UF
J 0
(-3725 5625);
DISPLAY 0.510638 (-3725 5625);
FORCEPROP 1 LAST PACK_TYPE C0805
J 0
(-3725 5375);
DISPLAY 0.510638 (-3725 5375);
FORCEPROP 1 LAST VOLTAGE 16V
J 0
(-3725 5575);
DISPLAY 0.510638 (-3725 5575);
FORCEPROP 1 LAST LOCATION PC1676
J 0
(-3725 5675);
DISPLAY 0.510638 (-3725 5675);
FORCEPROP 1 LASTPIN (-3775 5650) $PN 1
J 0
(-3765 5630);
DISPLAY 0.787234 (-3765 5630);
PAINT MONO (-3765 5630);
FORCEPROP 1 LASTPIN (-3775 5450) $PN 2
J 0
(-3765 5430);
DISPLAY 0.787234 (-3765 5430);
PAINT MONO (-3765 5430);
FORCEPROP 2 LAST CDS_LIB pure_quanta
J 0
(-3775 5550);
DISPLAY INVISIBLE (-3775 5550);
FORCEPROP 1 LAST PATH I79
J 0
(-3725 5700);
DISPLAY 0.978723 (-3725 5700);
PAINT WHITE (-3725 5700);
DISPLAY INVISIBLE (-3725 5700);
FORCEPROP 0 LAST $SEC 1
J 0
(-3725 5700);
DISPLAY 0.680851 (-3725 5700);
PAINT MONO (-3725 5700);
DISPLAY INVISIBLE (-3725 5700);
FORCEPROP 0 LAST CDS_SEC 1
J 0
(-3725 5700);
DISPLAY 1.021277 (-3725 5700);
DISPLAY INVISIBLE (-3725 5700);
FORCEADD UNIVERSAL_GND..1
(-10700 2300);
FORCEPROP 3 LASTPIN (-10700 2350) SIG_NAME GND\g
J 0
(-10690 2360);
DISPLAY 0.659574 (-10690 2360);
PAINT MONO (-10690 2360);
DISPLAY INVISIBLE (-10690 2360);
FORCEPROP 1 LAST HDL_POWER GND
J 1
(-10675 2225);
DISPLAY 0.872340 (-10675 2225);
PAINT GREEN (-10675 2225);
DISPLAY INVISIBLE (-10675 2225);
FORCEPROP 2 LAST CDS_LIB logical_power
J 0
(-10700 2300);
PAINT MONO (-10700 2300);
DISPLAY INVISIBLE (-10700 2300);
FORCEPROP 1 LAST PATH I8
J 0
(-10625 2300);
DISPLAY 0.872340 (-10625 2300);
PAINT AQUA (-10625 2300);
DISPLAY INVISIBLE (-10625 2300);
FORCEADD Q_CAPP..1
(-3500 5550);
FORCEPROP 1 LAST PART_NUMBER CC72703MD38
J 0
(-3450 5375);
DISPLAY 0.617021 (-3450 5375);
PAINT BLUE (-3450 5375);
DISPLAY INVISIBLE (-3450 5375);
FORCEPROP 1 LAST PACK_TYPE THLF
J 0
(-3450 5425);
DISPLAY 0.617021 (-3450 5425);
PAINT SKYBLUE (-3450 5425);
FORCEPROP 1 LAST TOLERANCE 20%
J 0
(-3450 5575);
DISPLAY 0.617021 (-3450 5575);
PAINT SKYBLUE (-3450 5575);
FORCEPROP 1 LAST MATERIAL OSCON
J 0
(-3450 5475);
DISPLAY 0.617021 (-3450 5475);
PAINT SKYBLUE (-3450 5475);
FORCEPROP 1 LAST VALUE 270UF
J 0
(-3450 5625);
DISPLAY 0.617021 (-3450 5625);
PAINT SKYBLUE (-3450 5625);
FORCEPROP 1 LAST VOLTAGE 16V
J 0
(-3450 5525);
DISPLAY 0.617021 (-3450 5525);
PAINT SKYBLUE (-3450 5525);
FORCEPROP 1 LAST LOCATION PC1189
J 0
(-3450 5675);
DISPLAY 0.617021 (-3450 5675);
PAINT AQUA (-3450 5675);
FORCEPROP 1 LASTPIN (-3500 5650) $PN 1
J 0
(-3490 5635);
DISPLAY 0.617021 (-3490 5635);
PAINT MONO (-3490 5635);
FORCEPROP 1 LASTPIN (-3500 5450) $PN 2
J 0
(-3490 5435);
DISPLAY 0.617021 (-3490 5435);
PAINT MONO (-3490 5435);
FORCEPROP 2 LAST CDS_LIB pure_quanta
J 0
(-3500 5550);
DISPLAY INVISIBLE (-3500 5550);
FORCEPROP 1 LAST PATH I80
J 0
(-3450 5700);
DISPLAY 0.978723 (-3450 5700);
DISPLAY INVISIBLE (-3450 5700);
FORCEPROP 1 LAST LOCATION PC1189
J 0
(-3450 5725);
DISPLAY 1.021277 (-3450 5725);
PAINT AQUA (-3450 5725);
DISPLAY INVISIBLE (-3450 5725);
FORCEPROP 0 LAST $SEC 1
J 0
(-3450 5725);
DISPLAY 0.680851 (-3450 5725);
PAINT MONO (-3450 5725);
DISPLAY INVISIBLE (-3450 5725);
FORCEPROP 0 LAST CDS_SEC 1
J 0
(-3450 5725);
DISPLAY 1.021277 (-3450 5725);
DISPLAY INVISIBLE (-3450 5725);
FORCEADD VCC15..1
(-3425 5925);
FORCEPROP 3 LASTPIN (-3425 5875) SIG_NAME SW_P12V_PVCCFA_EHV_FIVRA_CPU0_R\g
J 0
(-3415 5885);
DISPLAY 0.659574 (-3415 5885);
PAINT MONO (-3415 5885);
DISPLAY INVISIBLE (-3415 5885);
FORCEPROP 1 LAST HDL_POWER SW_P12V_PVCCFA_EHV_FIVRA_CPU0_R
J 1
(-3375 5975);
DISPLAY 0.617021 (-3375 5975);
PAINT GREEN (-3375 5975);
FORCEPROP 2 LAST CDS_LIB logical_power
J 0
(-3425 5925);
DISPLAY INVISIBLE (-3425 5925);
FORCEPROP 1 LAST PATH I81
J 0
(-3375 5950);
DISPLAY 0.872340 (-3375 5950);
PAINT AQUA (-3375 5950);
DISPLAY INVISIBLE (-3375 5950);
FORCEADD ISL99390FRZTR5935..1
(-9175 4900);
FORCEPROP 1 LAST PART_NUMBER AL099390004
J 0
(-9475 5700);
DISPLAY 0.617021 (-9475 5700);
PAINT BLUE (-9475 5700);
DISPLAY INVISIBLE (-9475 5700);
FORCEPROP 2 LAST PART_TYPE SMLF
J 0
(-9475 5900);
DISPLAY 0.638298 (-9475 5900);
FORCEPROP 2 LAST VALUE ISL99390FRZ-TR5935
J 0
(-9475 5850);
DISPLAY 0.617021 (-9475 5850);
PAINT SKYBLUE (-9475 5850);
FORCEPROP 1 LAST MATERIAL IC
J 0
(-9475 5625);
DISPLAY 0.617021 (-9475 5625);
PAINT RED (-9475 5625);
FORCEPROP 1 LAST LOCATION PU71_P0_3
J 0
(-9475 5775);
DISPLAY 0.617021 (-9475 5775);
PAINT AQUA (-9475 5775);
FORCEPROP 2 LASTPIN (-8775 4450) $PN 2
J 0
(-8765 4460);
DISPLAY 0.617021 (-8765 4460);
PAINT MONO (-8765 4460);
FORCEPROP 2 LASTPIN (-8775 5250) $PN 33
J 0
(-8765 5260);
DISPLAY 0.617021 (-8765 5260);
PAINT MONO (-8765 5260);
FORCEPROP 2 LASTPIN (-9625 4650) $PN 31
J 2
(-9635 4660);
DISPLAY 0.617021 (-9635 4660);
PAINT MONO (-9635 4660);
FORCEPROP 2 LASTPIN (-9625 5050) $PN 35
J 2
(-9635 5060);
DISPLAY 0.617021 (-9635 5060);
PAINT MONO (-9635 5060);
FORCEPROP 2 LASTPIN (-8775 4600) $PN 6
J 0
(-8765 4610);
DISPLAY 0.617021 (-8765 4610);
PAINT MONO (-8765 4610);
FORCEPROP 2 LASTPIN (-8775 4550) $PN 41
J 0
(-8765 4560);
DISPLAY 0.617021 (-8765 4560);
PAINT MONO (-8765 4560);
FORCEPROP 2 LASTPIN (-9625 4900) $PN 38
J 2
(-9635 4910);
DISPLAY 0.617021 (-9635 4910);
PAINT MONO (-9635 4910);
FORCEPROP 2 LASTPIN (-9625 4600) $PN 37
J 2
(-9635 4610);
DISPLAY 0.617021 (-9635 4610);
PAINT MONO (-9635 4610);
FORCEPROP 2 LASTPIN (-8775 4400) $PN 5
J 0
(-8765 4410);
DISPLAY 0.617021 (-8765 4410);
PAINT MONO (-8765 4410);
FORCEPROP 2 LASTPIN (-8775 4350) $PN 7_9-20_24
J 0
(-8765 4360);
DISPLAY 0.617021 (-8765 4360);
PAINT MONO (-8765 4360);
FORCEPROP 2 LASTPIN (-8775 4300) $PN 40
J 0
(-8765 4310);
DISPLAY 0.617021 (-8765 4310);
PAINT MONO (-8765 4310);
FORCEPROP 2 LASTPIN (-8775 5000) $PN 32
J 0
(-8765 5010);
DISPLAY 0.617021 (-8765 5010);
PAINT MONO (-8765 5010);
FORCEPROP 2 LASTPIN (-9625 5550) $PN 4
J 2
(-9635 5560);
DISPLAY 0.617021 (-9635 5560);
PAINT MONO (-9635 5560);
FORCEPROP 2 LASTPIN (-9625 4300) $PN 34
J 2
(-9635 4310);
DISPLAY 0.617021 (-9635 4310);
PAINT MONO (-9635 4310);
FORCEPROP 2 LASTPIN (-9625 4800) $PN 39
J 2
(-9635 4810);
DISPLAY 0.617021 (-9635 4810);
PAINT MONO (-9635 4810);
FORCEPROP 2 LASTPIN (-8775 4900) $PN 10_19
J 0
(-8765 4910);
DISPLAY 0.617021 (-8765 4910);
PAINT MONO (-8765 4910);
FORCEPROP 2 LASTPIN (-9625 4400) $PN 36
J 2
(-9635 4410);
DISPLAY 0.617021 (-9635 4410);
PAINT MONO (-9635 4410);
FORCEPROP 2 LASTPIN (-9625 5250) $PN 3
J 2
(-9635 5260);
DISPLAY 0.617021 (-9635 5260);
PAINT MONO (-9635 5260);
FORCEPROP 2 LASTPIN (-8775 5550) $PN 25_29
J 0
(-8765 5560);
DISPLAY 0.617021 (-8765 5560);
PAINT MONO (-8765 5560);
FORCEPROP 2 LASTPIN (-8775 5500) $PN 30
J 0
(-8765 5510);
DISPLAY 0.617021 (-8765 5510);
PAINT MONO (-8765 5510);
FORCEPROP 2 LASTPIN (-8775 4650) $PN 1
J 0
(-8765 4660);
DISPLAY 0.617021 (-8765 4660);
PAINT MONO (-8765 4660);
FORCEPROP 1 LAST NEEDS_NO_SIZE TRUE
J 0
(-9175 4900);
DISPLAY 0.723404 (-9175 4900);
PAINT GREEN (-9175 4900);
DISPLAY INVISIBLE (-9175 4900);
FORCEPROP 1 LAST CDS_LMAN_SYM_OUTLINE -300,700,250,-650
J 0
(-9175 4900);
DISPLAY 0.468085 (-9175 4900);
PAINT GREEN (-9175 4900);
DISPLAY INVISIBLE (-9175 4900);
FORCEPROP 2 LAST CDS_LIB pure_quanta
J 0
(-9175 4900);
DISPLAY INVISIBLE (-9175 4900);
FORCEPROP 1 LAST PATH I82
J 0
(-9175 4900);
DISPLAY 0.723404 (-9175 4900);
PAINT GREEN (-9175 4900);
DISPLAY INVISIBLE (-9175 4900);
FORCEPROP 2 LAST $SEC 1
J 0
(-9475 5825);
DISPLAY 0.680851 (-9475 5825);
PAINT MONO (-9475 5825);
DISPLAY INVISIBLE (-9475 5825);
FORCEPROP 2 LAST CDS_SEC 1
J 0
(-9425 5900);
DISPLAY 1.021277 (-9425 5900);
DISPLAY INVISIBLE (-9425 5900);
FORCEADD Q_CAP..2
(-10425 1900);
FORCEPROP 1 LAST PART_NUMBER CH4104K1B00
J 1
(-10175 1950);
DISPLAY 0.617021 (-10175 1950);
PAINT BLUE (-10175 1950);
DISPLAY INVISIBLE (-10175 1950);
FORCEPROP 1 LAST VOLTAGE 25V
J 0
(-10125 1900);
DISPLAY 0.617021 (-10125 1900);
PAINT SKYBLUE (-10125 1900);
FORCEPROP 1 LAST MATERIAL X7R
J 0
(-9975 1950);
DISPLAY 0.617021 (-9975 1950);
PAINT RED (-9975 1950);
FORCEPROP 1 LAST PACK_TYPE 0402
J 1
(-9950 1900);
DISPLAY 0.617021 (-9950 1900);
PAINT SKYBLUE (-9950 1900);
FORCEPROP 1 LAST TOLERANCE 10%
J 2
(-9800 1925);
DISPLAY 0.617021 (-9800 1925);
PAINT SKYBLUE (-9800 1925);
FORCEPROP 1 LAST VALUE 0.1UF
J 2
(-10150 1900);
DISPLAY 0.617021 (-10150 1900);
PAINT SKYBLUE (-10150 1900);
FORCEPROP 1 LAST LOCATION PC1352
J 1
(-10625 1900);
DISPLAY 0.617021 (-10625 1900);
PAINT AQUA (-10625 1900);
FORCEPROP 1 LASTPIN (-10525 1900) $PN 1
J 0
(-10535 1915);
DISPLAY 0.617021 (-10535 1915);
FORCEPROP 1 LASTPIN (-10325 1900) $PN 2
J 0
(-10340 1915);
DISPLAY 0.617021 (-10340 1915);
FORCEPROP 2 LAST CDS_LIB pure_quanta
J 0
(-10425 1900);
PAINT MONO (-10425 1900);
DISPLAY INVISIBLE (-10425 1900);
FORCEPROP 1 LAST PATH I9
J 0
(-10425 2100);
DISPLAY 0.978723 (-10425 2100);
PAINT WHITE (-10425 2100);
DISPLAY INVISIBLE (-10425 2100);
FORCEPROP 2 LAST $SEC 1
J 0
(-10425 2150);
DISPLAY 0.680851 (-10425 2150);
PAINT MONO (-10425 2150);
DISPLAY INVISIBLE (-10425 2150);
FORCEPROP 2 LAST CDS_SEC 1
J 0
(-10425 2150);
DISPLAY 1.021277 (-10425 2150);
DISPLAY INVISIBLE (-10425 2150);
FORCEADD DNS..1
(-11200 1575);
PAINT RED (-11200 1575);
FORCEPROP 1 LAST COMMENT_BODY TRUE
R 1
J 0
(-11125 1350);
DISPLAY 0.872340 (-11125 1350);
PAINT GREEN (-11125 1350);
DISPLAY INVISIBLE (-11125 1350);
FORCEPROP 2 LAST CDS_LIB mstr_misc
J 0
(-11200 1575);
PAINT MONO (-11200 1575);
DISPLAY INVISIBLE (-11200 1575);
FORCEADD DNS..1
(-11175 4425);
PAINT RED (-11175 4425);
FORCEPROP 1 LAST COMMENT_BODY TRUE
R 1
J 0
(-11100 4200);
DISPLAY 0.872340 (-11100 4200);
PAINT GREEN (-11100 4200);
DISPLAY INVISIBLE (-11100 4200);
FORCEPROP 2 LAST CDS_LIB mstr_misc
J 0
(-11175 4425);
PAINT MONO (-11175 4425);
DISPLAY INVISIBLE (-11175 4425);
FORCEADD QUANTA_TITLE_BLOCK_C..1
(-2600 225);
FORCEPROP 0 LAST CDS_CON_LAST_MODIFIED Fri Aug 25 14:04:43 2023
J 0
(-4485 240);
DISPLAY INVISIBLE (-4485 240);
FORCEPROP 1 LAST CUSTOM_TXT_CDS <CON_LAST_MODIFIED>
J 0
(-4485 240);
DISPLAY 0.978723 (-4485 240);
FORCEPROP 2 LAST CUSTOM_TXT_CDS <XR_PAGE_TITLE>
J 0
(-10490 5475);
DISPLAY 0.638298 (-10490 5475);
PAINT PINK (-10490 5475);
DISPLAY INVISIBLE (-10490 5475);
FORCEPROP 1 LAST CUSTOM_TXT_CDS <NAME_2>
J 0
(-5775 275);
FORCEPROP 1 LAST CUSTOM_TXT_CDS <NAME_1>
J 0
(-5775 400);
FORCEPROP 1 LAST CUSTOM_TXT_CDS <Q_NUMBER>
J 0
(-4003 328);
DISPLAY 1.212766 (-4003 328);
FORCEPROP 1 LAST CUSTOM_TXT_CDS <Q_PROJ>
J 0
(-4982 327);
DISPLAY 1.212766 (-4982 327);
FORCEPROP 1 LAST CUSTOM_TXT_CDS <Q_REV>
J 0
(-2784 328);
DISPLAY 1.212766 (-2784 328);
FORCEPROP 1 LAST CUSTOM_TXT_CDS <CON_PAGE_NUM> OF <CON_TOTAL_PAGES>
J 0
(-3046 243);
DISPLAY 0.978723 (-3046 243);
FORCEPROP 1 LAST Q_TITLE VCCFA_EHV_FIVRA CPU0 VR PHASE 3&4(7/7)
J 0
(-11900 275);
DISPLAY 2.446809 (-11900 275);
PAINT GREEN (-11900 275);
FORCEPROP 1 LAST Q_DEPT 
J 1
(-6363 274);
DISPLAY 1.957447 (-6363 274);
PAINT GREEN (-6363 274);
FORCEPROP 2 LAST CDS_XR_PAGE_TITLE CR-272 : @S9S_MB_2U_LIB.S9S_MB_2U(SCH_1):PAGE272
J 0
(-10490 5475);
DISPLAY 0.638298 (-10490 5475);
PAINT PINK (-10490 5475);
DISPLAY INVISIBLE (-10490 5475);
FORCEPROP 2 LAST CDS_LIB pure_quanta
J 0
(-2600 225);
DISPLAY INVISIBLE (-2600 225);
FORCEPROP 1 LAST CDS_LMAN_SYM_OUTLINE -9475,6775,100,-125
J 0
(-2600 225);
DISPLAY 0.468085 (-2600 225);
PAINT GREEN (-2600 225);
DISPLAY INVISIBLE (-2600 225);
FORCEPROP 2 LAST PAGE_BORDER TRUE
J 0
(-10490 5475);
DISPLAY 0.638298 (-10490 5475);
PAINT PINK (-10490 5475);
DISPLAY INVISIBLE (-10490 5475);
FORCEPROP 1 LAST COMMENT_BODY TRUE
J 0
(-2588 212);
DISPLAY 0.978723 (-2588 212);
PAINT GREEN (-2588 212);
DISPLAY INVISIBLE (-2588 212);
WIRE 16 -1 (-10700 3250)(-10700 3150);
WIRE 16 -1 (-10700 6025)(-10700 5950);
WIRE 16 -1 (-6575 3325)(-6575 3250);
WIRE 16 -1 (-6575 6125)(-6575 6050);
WIRE 16 -1 (-5450 5900)(-5450 5775);
WIRE 16 -1 (-4275 2250)(-4275 2100);
WIRE 16 -1 (-3025 3775)(-3025 3725);
WIRE 16 -1 (-4275 5050)(-4275 4900);
WIRE 16 -1 (-3425 5875)(-3425 5775);
WIRE 16 -1 (-11250 1900)(-11250 1875);
WIRE 16 -1 (-11250 1900)(-10525 1900);
WIRE 16 -1 (-11200 1500)(-11200 1425);
WIRE 16 -1 (-10700 2450)(-10700 2350);
WIRE 16 -1 (-11175 4350)(-11175 4275);
WIRE 16 -1 (-10175 2850)(-10175 2750);
WIRE 16 -1 (-11250 4700)(-11250 4675);
WIRE 16 -1 (-11250 4700)(-10525 4700);
WIRE 16 -1 (-10700 5250)(-10700 5150);
WIRE 16 -1 (-10175 5650)(-10175 5550);
WIRE 16 -1 (-8525 1500)(-8525 1425);
WIRE 16 -1 (-8525 1550)(-8525 1500);
WIRE 16 -1 (-8775 1500)(-8525 1500);
WIRE 16 -1 (-8525 4300)(-8525 4225);
WIRE 16 -1 (-8525 4350)(-8525 4300);
WIRE 16 -1 (-8775 4300)(-8525 4300);
WIRE 16 -1 (-6575 2675)(-6575 2750);
WIRE 16 -1 (-6575 5475)(-6575 5550);
WIRE 16 -1 (-5450 5375)(-5450 5475);
WIRE 16 -1 (-4275 1575)(-4275 1675);
WIRE 16 -1 (-4275 4375)(-4275 4475);
WIRE 16 -1 (-3025 3300)(-3025 3200);
WIRE 16 -1 (-3475 3300)(-3025 3300);
WIRE 16 -1 (-3025 3400)(-3025 3300);
WIRE 16 -1 (-3500 5350)(-3500 5300);
WIRE 16 -1 (-3775 5350)(-3500 5350);
WIRE 16 -1 (-3500 5450)(-3500 5350);
WIRE 16 -1 (-3775 5450)(-3775 5350);
WIRE 16 -1 (-4050 5450)(-4050 5350);
WIRE 16 -1 (-4050 5350)(-3775 5350);
WIRE 16 -1 (-4325 5450)(-4325 5350);
WIRE 16 -1 (-4325 5350)(-4050 5350);
WIRE 16 -1 (-4625 5350)(-4325 5350);
WIRE 16 -1 (-4625 5450)(-4625 5350);
WIRE 16 -1 (-3500 5775)(-3500 5650);
WIRE 16 -1 (-3425 5775)(-3500 5775);
WIRE 16 -1 (-3775 5650)(-3775 5775);
WIRE 16 -1 (-3775 5775)(-3500 5775);
WIRE 16 -1 (-4050 5650)(-4050 5775);
WIRE 16 -1 (-4050 5775)(-3775 5775);
WIRE 16 -1 (-4325 5650)(-4325 5775);
WIRE 16 -1 (-4325 5775)(-4050 5775);
WIRE 16 -1 (-4625 5650)(-4625 5775);
WIRE 16 -1 (-4625 5775)(-4325 5775);
WIRE 16 -1 (-4925 5775)(-4625 5775);
WIRE 16 -1 (-3475 3400)(-3475 3300);
WIRE 16 -1 (-3975 3400)(-3975 3300);
WIRE 16 -1 (-3475 3300)(-3975 3300);
WIRE 16 -1 (-4500 3300)(-4500 3400);
WIRE 16 -1 (-4500 3300)(-3975 3300);
WIRE 16 -1 (-5025 3300)(-4500 3300);
WIRE 16 -1 (-5025 3400)(-5025 3300);
WIRE 16 -1 (-3025 3725)(-3025 3600);
WIRE 16 -1 (-3475 3600)(-3475 3725);
WIRE 16 -1 (-3475 3725)(-3025 3725);
WIRE 16 -1 (-3975 3600)(-3975 3725);
WIRE 16 -1 (-3475 3725)(-3975 3725);
WIRE 16 -1 (-4500 3725)(-4500 3600);
WIRE 16 -1 (-4500 3725)(-3975 3725);
WIRE 16 -1 (-5025 3725)(-4500 3725);
WIRE 16 -1 (-5025 3600)(-5025 3725);
WIRE 16 -1 (-4575 4800)(-4575 4900);
WIRE 16 -1 (-4275 4900)(-4575 4900);
WIRE 16 -1 (-6200 4650)(-6375 4650);
WIRE 16 -1 (-5000 4900)(-5000 4800);
WIRE 16 -1 (-5000 4900)(-4575 4900);
WIRE 16 -1 (-5425 4800)(-5425 4900);
WIRE 16 -1 (-5425 4900)(-5000 4900);
WIRE 16 -1 (-6200 4900)(-6200 4650);
WIRE 16 -1 (-6200 4900)(-6375 4900);
WIRE 16 -1 (-6200 4900)(-5425 4900);
WIRE 16 -1 (-4575 4600)(-4575 4475);
WIRE 16 -1 (-4275 4475)(-4575 4475);
WIRE 16 -1 (-5000 4475)(-5000 4600);
WIRE 16 -1 (-4575 4475)(-5000 4475);
WIRE 16 -1 (-5425 4475)(-5000 4475);
WIRE 16 -1 (-5425 4600)(-5425 4475);
WIRE 16 -1 (-4575 2000)(-4575 2100);
WIRE 16 -1 (-4275 2100)(-4575 2100);
WIRE 16 -1 (-6200 1850)(-6375 1850);
WIRE 16 -1 (-5000 2100)(-5000 2000);
WIRE 16 -1 (-5000 2100)(-4575 2100);
WIRE 16 -1 (-5450 2000)(-5450 2100);
WIRE 16 -1 (-5000 2100)(-5450 2100);
WIRE 16 -1 (-6200 2100)(-6200 1850);
WIRE 16 -1 (-6375 2100)(-6200 2100);
WIRE 16 -1 (-6200 2100)(-5450 2100);
WIRE 16 -1 (-4575 1800)(-4575 1675);
WIRE 16 -1 (-4275 1675)(-4575 1675);
WIRE 16 -1 (-5000 1675)(-5000 1800);
WIRE 16 -1 (-4575 1675)(-5000 1675);
WIRE 16 -1 (-5000 1675)(-5450 1675);
WIRE 16 -1 (-5450 1800)(-5450 1675);
WIRE 16 -1 (-5450 5675)(-5450 5775);
WIRE 16 -1 (-5450 5775)(-5125 5775);
WIRE 16 -1 (-6725 5700)(-6725 5550);
WIRE 16 -1 (-6575 5550)(-6725 5550);
WIRE 16 -1 (-7175 5700)(-7175 5550);
WIRE 16 -1 (-6725 5550)(-7175 5550);
WIRE 16 -1 (-7575 5550)(-7175 5550);
WIRE 16 -1 (-7575 5700)(-7575 5550);
WIRE 16 -1 (-7975 5700)(-7975 5550);
WIRE 16 -1 (-7575 5550)(-7975 5550);
WIRE 16 -1 (-8375 5550)(-7975 5550);
WIRE 16 -1 (-8375 5700)(-8375 5550);
WIRE 16 -1 (-6725 5900)(-6725 6050);
WIRE 16 -1 (-6575 6050)(-6725 6050);
WIRE 16 -1 (-7175 5900)(-7175 6050);
WIRE 16 -1 (-6725 6050)(-7175 6050);
WIRE 16 -1 (-7575 6050)(-7575 5900);
WIRE 16 -1 (-7575 6050)(-7175 6050);
WIRE 16 -1 (-8600 5500)(-8775 5500);
WIRE 16 -1 (-8775 5550)(-8600 5550);
WIRE 16 -1 (-8600 5550)(-8600 5500);
WIRE 16 -1 (-7975 5900)(-7975 6050);
WIRE 16 -1 (-7975 6050)(-7575 6050);
WIRE 16 -1 (-8375 5900)(-8375 6050);
WIRE 16 -1 (-8375 6050)(-7975 6050);
WIRE 16 -1 (-8600 6050)(-8600 5550);
WIRE 16 -1 (-8600 6050)(-8375 6050);
WIRE 16 -1 (-8775 4900)(-6575 4900);
FORCEPROP 2 LAST SIG_NAME SW_PVCCFA_EHV_FIVRA_CPU0_SW3
J 0
(-8585 4910);
DISPLAY 0.617021 (-8585 4910);
WIRE 16 -1 (-8775 4650)(-6575 4650);
FORCEPROP 2 LAST SIG_NAME PVCCFA_EHV_FIVRA_CPU0_VOS3
J 0
(-8585 4660);
DISPLAY 0.617021 (-8585 4660);
WIRE 16 -1 (-6750 5350)(-6750 5275);
WIRE 16 -1 (-7575 5350)(-6750 5350);
FORCEPROP 2 LAST SIG_NAME SW_PVCCFA_EHV_FIVRA_CPU0_BOOT3_R
J 0
(-7285 5360);
DISPLAY 0.617021 (-7285 5360);
WIRE 16 -1 (-6750 5000)(-6750 5075);
WIRE 16 -1 (-8775 5000)(-6750 5000);
FORCEPROP 2 LAST SIG_NAME SW_PVCCFA_EHV_FIVRA_CPU0_BOOTR3
J 0
(-8585 5010);
DISPLAY 0.617021 (-8585 5010);
WIRE 16 -1 (-8625 5350)(-7775 5350);
WIRE 16 -1 (-8625 5250)(-8625 5350);
FORCEPROP 2 LAST SIG_NAME SW_PVCCFA_EHV_FIVRA_CPU0_BOOT3
J 0
(-8835 5360);
DISPLAY 0.617021 (-8835 5360);
WIRE 16 -1 (-8775 5250)(-8625 5250);
WIRE 16 -1 (-8525 4450)(-8775 4450);
WIRE 16 -1 (-8775 4400)(-8525 4400);
WIRE 16 -1 (-8525 4400)(-8525 4450);
WIRE 16 -1 (-8525 4400)(-8525 4350);
WIRE 16 -1 (-8775 4350)(-8525 4350);
WIRE 16 -1 (-6725 2900)(-6725 2750);
WIRE 16 -1 (-6575 2750)(-6725 2750);
WIRE 16 -1 (-7175 2900)(-7175 2750);
WIRE 16 -1 (-6725 2750)(-7175 2750);
WIRE 16 -1 (-7575 2900)(-7575 2750);
WIRE 16 -1 (-7575 2750)(-7175 2750);
WIRE 16 -1 (-7975 2900)(-7975 2750);
WIRE 16 -1 (-7575 2750)(-7975 2750);
WIRE 16 -1 (-8375 2750)(-7975 2750);
WIRE 16 -1 (-8375 2900)(-8375 2750);
WIRE 16 -1 (-6725 3100)(-6725 3250);
WIRE 16 -1 (-6575 3250)(-6725 3250);
WIRE 16 -1 (-7175 3100)(-7175 3250);
WIRE 16 -1 (-6725 3250)(-7175 3250);
WIRE 16 -1 (-7575 3250)(-7575 3100);
WIRE 16 -1 (-7575 3250)(-7175 3250);
WIRE 16 -1 (-8600 2700)(-8775 2700);
WIRE 16 -1 (-8775 2750)(-8600 2750);
WIRE 16 -1 (-8600 2750)(-8600 2700);
WIRE 16 -1 (-7975 3100)(-7975 3250);
WIRE 16 -1 (-7975 3250)(-7575 3250);
WIRE 16 -1 (-8375 3100)(-8375 3250);
WIRE 16 -1 (-8375 3250)(-7975 3250);
WIRE 16 -1 (-8600 3250)(-8600 2750);
WIRE 16 -1 (-8600 3250)(-8375 3250);
WIRE 16 -1 (-8775 2100)(-6575 2100);
FORCEPROP 2 LAST SIG_NAME SW_PVCCFA_EHV_FIVRA_CPU0_SW4
J 0
(-8585 2110);
DISPLAY 0.617021 (-8585 2110);
WIRE 16 -1 (-6750 2550)(-6750 2475);
WIRE 16 -1 (-7575 2550)(-6750 2550);
FORCEPROP 2 LAST SIG_NAME SW_PVCCFA_EHV_FIVRA_CPU0_BOOT4_R
J 0
(-7285 2560);
DISPLAY 0.617021 (-7285 2560);
WIRE 16 -1 (-6750 2200)(-6750 2275);
WIRE 16 -1 (-8775 2200)(-6750 2200);
FORCEPROP 2 LAST SIG_NAME SW_PVCCFA_EHV_FIVRA_CPU0_BOOTR4
J 0
(-8585 2210);
DISPLAY 0.617021 (-8585 2210);
WIRE 16 -1 (-8775 1850)(-6575 1850);
FORCEPROP 2 LAST SIG_NAME PVCCFA_EHV_FIVRA_CPU0_VOS4
J 0
(-8585 1860);
DISPLAY 0.617021 (-8585 1860);
WIRE 16 -1 (-8625 2550)(-7775 2550);
WIRE 16 -1 (-8625 2450)(-8625 2550);
FORCEPROP 2 LAST SIG_NAME SW_PVCCFA_EHV_FIVRA_CPU0_BOOT4
J 0
(-8835 2560);
DISPLAY 0.617021 (-8835 2560);
WIRE 16 -1 (-8775 2450)(-8625 2450);
WIRE 16 -1 (-8775 1550)(-8525 1550);
WIRE 16 -1 (-8525 1650)(-8775 1650);
WIRE 16 -1 (-8775 1600)(-8525 1600);
WIRE 16 -1 (-8525 1600)(-8525 1550);
WIRE 16 -1 (-8525 1600)(-8525 1650);
WIRE 16 -1 (-9775 5550)(-9625 5550);
WIRE 16 -1 (-10700 5950)(-10700 5850);
WIRE 16 -1 (-10175 5950)(-10700 5950);
WIRE 16 -1 (-10175 5850)(-10175 5950);
WIRE 16 -1 (-9775 5550)(-9775 5950);
WIRE 16 -1 (-9775 5950)(-10175 5950);
WIRE 16 -1 (-9625 5050)(-9775 5050);
WIRE 16 -1 (-9775 5250)(-9775 5050);
WIRE 16 -1 (-9625 5250)(-9775 5250);
WIRE 16 -1 (-9775 5250)(-10450 5250);
FORCEPROP 0 LAST CDS_PHYS_NET_NAME PVCCFA_EHV_FIVRA_CPU0_VDD3
J 0
(-10385 5290);
PAINT MONO (-10385 5290);
DISPLAY INVISIBLE (-10385 5290);
FORCEPROP 2 LAST SIG_NAME PVCCFA_EHV_FIVRA_CPU0_VDD3
J 0
(-10410 5260);
DISPLAY 0.617021 (-10410 5260);
WIRE 16 -1 (-10450 5250)(-10450 5550);
WIRE 16 -1 (-10450 5550)(-10700 5550);
WIRE 16 -1 (-10700 5550)(-10700 5650);
WIRE 16 -1 (-10700 5450)(-10700 5550);
WIRE 16 -1 (-9625 4400)(-10650 4400);
FORCEPROP 2 LAST SIG_NAME PVCCFA_EHV_FIVRA_CPU0_BTSEN
J 0
(-10585 4410);
DISPLAY 0.617021 (-10585 4410);
WIRE 16 -1 (-9625 4900)(-10650 4900);
FORCEPROP 2 LAST SIG_NAME PVCCFA_EHV_FIVRA_CPU0_IMON3
J 0
(-10585 4910);
DISPLAY 0.617021 (-10585 4910);
WIRE 16 -1 (-9775 4700)(-10325 4700);
WIRE 16 -1 (-10650 4800)(-9775 4800);
FORCEPROP 2 LAST SIG_NAME PVCCIN_CPU0_VREF
J 0
(-10585 4810);
DISPLAY 0.617021 (-10585 4810);
WIRE 16 -1 (-9775 4800)(-9775 4700);
FORCEPROP 0 LAST CDS_PHYS_NET_NAME PVCCIN_CPU0_VREF
J 0
(-9775 4725);
PAINT MONO (-9775 4725);
DISPLAY INVISIBLE (-9775 4725);
WIRE 16 -1 (-9775 4800)(-9625 4800);
WIRE 16 -1 (-11175 4600)(-11175 4550);
WIRE 16 -1 (-11175 4600)(-9625 4600);
FORCEPROP 0 LAST CDS_PHYS_NET_NAME PVCCFA_EHV_FIVRA_CPU0_LSET3
J 0
(-10585 4640);
PAINT MONO (-10585 4640);
DISPLAY INVISIBLE (-10585 4640);
FORCEPROP 2 LAST SIG_NAME PVCCFA_EHV_FIVRA_CPU0_LSET3
J 0
(-10585 4610);
DISPLAY 0.617021 (-10585 4610);
WIRE 16 -1 (-9775 2750)(-9625 2750);
WIRE 16 -1 (-10700 3150)(-10700 3050);
WIRE 16 -1 (-10175 3150)(-10700 3150);
WIRE 16 -1 (-10175 3050)(-10175 3150);
WIRE 16 -1 (-9775 2750)(-9775 3150);
WIRE 16 -1 (-9775 3150)(-10175 3150);
WIRE 16 -1 (-9625 4300)(-10650 4300);
FORCEPROP 2 LAST SIG_NAME PVCCFA_EHV_FIVRA_CPU0_PWM3
J 0
(-10585 4310);
DISPLAY 0.617021 (-10585 4310);
WIRE 16 -1 (-10700 2650)(-10700 2750);
WIRE 16 -1 (-10700 2750)(-10700 2850);
WIRE 16 -1 (-10450 2750)(-10700 2750);
WIRE 16 -1 (-10450 2450)(-10450 2750);
WIRE 16 -1 (-9775 2450)(-10450 2450);
FORCEPROP 0 LAST CDS_PHYS_NET_NAME PVCCFA_EHV_FIVRA_CPU0_VDD4
J 0
(-10385 2490);
PAINT MONO (-10385 2490);
DISPLAY INVISIBLE (-10385 2490);
FORCEPROP 2 LAST SIG_NAME PVCCFA_EHV_FIVRA_CPU0_VDD4
J 0
(-10410 2460);
DISPLAY 0.617021 (-10410 2460);
WIRE 16 -1 (-9625 2450)(-9775 2450);
WIRE 16 -1 (-9775 2450)(-9775 2250);
WIRE 16 -1 (-9625 2250)(-9775 2250);
WIRE 16 -1 (-9625 2100)(-10675 2100);
FORCEPROP 2 LAST SIG_NAME PVCCFA_EHV_FIVRA_CPU0_IMON4
J 0
(-10610 2110);
DISPLAY 0.617021 (-10610 2110);
WIRE 16 -1 (-9775 1900)(-10325 1900);
WIRE 16 -1 (-10675 2000)(-9775 2000);
FORCEPROP 2 LAST SIG_NAME PVCCIN_CPU0_VREF
J 0
(-10610 2010);
DISPLAY 0.617021 (-10610 2010);
WIRE 16 -1 (-9775 2000)(-9775 1900);
FORCEPROP 0 LAST CDS_PHYS_NET_NAME PVCCIN_CPU0_VREF
J 0
(-9775 1925);
PAINT MONO (-9775 1925);
DISPLAY INVISIBLE (-9775 1925);
WIRE 16 -1 (-9775 2000)(-9625 2000);
WIRE 16 -1 (-9625 1600)(-10675 1600);
FORCEPROP 2 LAST SIG_NAME PVCCFA_EHV_FIVRA_CPU0_BTSEN
J 0
(-10610 1610);
DISPLAY 0.617021 (-10610 1610);
WIRE 16 -1 (-9625 1500)(-10675 1500);
FORCEPROP 2 LAST SIG_NAME PVCCFA_EHV_FIVRA_CPU0_PWM4
J 0
(-10610 1510);
DISPLAY 0.617021 (-10610 1510);
WIRE 16 -1 (-11200 1800)(-11200 1700);
WIRE 16 -1 (-11200 1800)(-9625 1800);
FORCEPROP 2 LAST SIG_NAME PVCCFA_EHV_FIVRA_CPU0_LSET4
J 0
(-10610 1810);
DISPLAY 0.617021 (-10610 1810);
DOT 1 (-9775 2000);
DOT 1 (-10700 3150);
DOT 1 (-10700 2750);
DOT 1 (-9775 2450);
DOT 1 (-10175 3150);
DOT 1 (-10700 5950);
DOT 1 (-10700 5550);
DOT 1 (-9775 4800);
DOT 1 (-9775 5250);
DOT 1 (-10175 5950);
DOT 1 (-8525 1500);
DOT 1 (-8525 1550);
DOT 1 (-8525 1600);
DOT 1 (-8600 2750);
DOT 1 (-8375 3250);
DOT 1 (-8525 4350);
DOT 1 (-8525 4300);
DOT 1 (-7975 2750);
DOT 1 (-7975 3250);
DOT 1 (-7575 2750);
DOT 1 (-7175 2750);
DOT 1 (-7575 3250);
DOT 1 (-7175 3250);
DOT 1 (-6200 2100);
DOT 1 (-5450 2100);
DOT 1 (-6725 2750);
DOT 1 (-6725 3250);
DOT 1 (-8525 4400);
DOT 1 (-8600 5550);
DOT 1 (-8375 6050);
DOT 1 (-7975 5550);
DOT 1 (-7975 6050);
DOT 1 (-7575 5550);
DOT 1 (-7175 5550);
DOT 1 (-7575 6050);
DOT 1 (-7175 6050);
DOT 1 (-6200 4900);
DOT 1 (-6725 5550);
DOT 1 (-6725 6050);
DOT 1 (-5425 4900);
DOT 1 (-5450 5775);
DOT 1 (-5000 1675);
DOT 1 (-4575 1675);
DOT 1 (-5000 2100);
DOT 1 (-4575 2100);
DOT 1 (-4500 3300);
DOT 1 (-4500 3725);
DOT 1 (-3975 3300);
DOT 1 (-3475 3300);
DOT 1 (-3025 3300);
DOT 1 (-3975 3725);
DOT 1 (-3475 3725);
DOT 1 (-3025 3725);
DOT 1 (-5000 4475);
DOT 1 (-5000 4900);
DOT 1 (-4575 4475);
DOT 1 (-4575 4900);
DOT 1 (-4325 5350);
DOT 1 (-4050 5350);
DOT 1 (-4625 5775);
DOT 1 (-4325 5775);
DOT 1 (-4050 5775);
DOT 1 (-3775 5350);
DOT 1 (-3500 5350);
DOT 1 (-3775 5775);
DOT 1 (-3500 5775);
FORCENOTE
20211013 MODIFY FOR GT
(-11800 6700) 0;
DISPLAY LEFT (-11800 6700);
DISPLAY 1.595745 (-11800 6700);
PAINT PINK (-11800 6700);
FORCENOTE
PVCCFA_EHV_FIVRA_CPU0_PHASE3
(-9975 6075) 0;
DISPLAY LEFT (-9975 6075);
DISPLAY 1.021277 (-9975 6075);
PAINT WHITE (-9975 6075);
FORCENOTE
PVCCFA_EHV_FIVRA_CPU0_PHASE4
(-9950 3275) 0;
DISPLAY LEFT (-9950 3275);
DISPLAY 1.021277 (-9950 3275);
PAINT WHITE (-9950 3275);
FORCENOTE
DCR = 0.103M OHM
(-6000 2150) 0;
DISPLAY LEFT (-6000 2150);
DISPLAY 1.021277 (-6000 2150);
FORCENOTE
ISAT = 90A @ 100C
(-6000 2225) 0;
DISPLAY LEFT (-6000 2225);
DISPLAY 1.021277 (-6000 2225);
FORCENOTE
10.0*7.5*12.0
(-6000 2300) 0;
DISPLAY LEFT (-6000 2300);
DISPLAY 1.021277 (-6000 2300);
FORCENOTE
PG2323.131HLT
(-6000 2375) 0;
DISPLAY LEFT (-6000 2375);
DISPLAY 1.021277 (-6000 2375);
FORCENOTE
PG2323.131HLT
(-6100 5225) 0;
DISPLAY LEFT (-6100 5225);
DISPLAY 1.021277 (-6100 5225);
FORCENOTE
10.0*7.5*12.0
(-6100 5150) 0;
DISPLAY LEFT (-6100 5150);
DISPLAY 1.021277 (-6100 5150);
FORCENOTE
ISAT = 90A @ 100C
(-6100 5075) 0;
DISPLAY LEFT (-6100 5075);
DISPLAY 1.021277 (-6100 5075);
FORCENOTE
DCR = 0.103M OHM
(-6100 5000) 0;
DISPLAY LEFT (-6100 5000);
DISPLAY 1.021277 (-6100 5000);
FORCENOTE
HCBS4545-101
(-4775 6050) 0;
DISPLAY LEFT (-4775 6050);
DISPLAY 0.808511 (-4775 6050);
FORCENOTE
4.5*4.5*4.5
(-4775 5975) 0;
DISPLAY LEFT (-4775 5975);
DISPLAY 0.808511 (-4775 5975);
FORCENOTE
ISAT = 13A @ 100C
(-4775 5900) 0;
DISPLAY LEFT (-4775 5900);
DISPLAY 0.808511 (-4775 5900);
FORCENOTE
DCR = 0.12M OHM
(-4775 5825) 0;
DISPLAY LEFT (-4775 5825);
DISPLAY 0.808511 (-4775 5825);
FORCENOTE
ESR=9.5M OHM
(-3450 5325) 0;
DISPLAY LEFT (-3450 5325);
DISPLAY 0.638298 (-3450 5325);
QUIT
